# Altium SchDoc records: 07-FPGA.SchDoc
|HEADER=Protel for Windows - Schematic Capture Binary File Version 5.0|Weight=1290|MinorVersion=7
|RECORD=31|FontIdCount=5|Size1=10|FontName1=Times New Roman|Size2=8|FontName2=Arial|Size3=10|FontName3=Arial|Size4=12|Underline4=T|FontName4=Arial|Size5=11|FontName5=Arial|UseMBCS=T|IsBOC=T|HotSpotGridOn=T|HotSpotGridSize=2|SheetStyle=12|SystemFont=3|BorderOn=T|SheetNumberSpaceSize=12|AreaColor=16317695|SnapGridOn=T|SnapGridSize=5|VisibleGridOn=T|VisibleGridSize=10|CustomX=2338|CustomX_Frac=58268|CustomY=1653|CustomY_Frac=54331|CustomXZones=8|CustomYZones=6|CustomMarginWidth=19|CustomMarginWidth_Frac=80000|ShowTemplateGraphics=T|TemplateFileName=C:\Users\<user>\Documents\Altium\AD20\Templates\Timecard.SchDot|Display_Unit=0
|RECORD=39|IsNotAccesible=T|OwnerPartId=-1|FileName=C:\Users\<user>\Documents\Altium\AD20\Templates\Timecard.SchDot
|RECORD=4|OwnerIndex=1|OwnerPartId=-1|Location.X=1594|Location.Y=39|Color=8388608|FontID=4|Text=timingcard.com|URL=http://timingcard.com
|RECORD=6|OwnerIndex=1|IndexInSheet=1|OwnerPartId=-1|LocationCount=2|X1=1680|Y1=35|X2=1576|Y2=35
|RECORD=4|OwnerIndex=1|IndexInSheet=2|OwnerPartId=-1|Location.X=1615|Location.Y=27|Justification=4|Color=16711680|FontID=5|Text==SheetNumber
|RECORD=4|OwnerIndex=1|IndexInSheet=3|OwnerPartId=-1|Location.X=1581|Location.X_Frac=42446|Location.Y=29|Location.Y_Frac=96838|Justification=3|FontID=2|Text=SHEET
|RECORD=4|OwnerIndex=1|IndexInSheet=4|OwnerPartId=-1|Location.X=1639|Location.X_Frac=42446|Location.Y=29|Location.Y_Frac=96838|Justification=3|FontID=2|Text=OF
|RECORD=6|OwnerIndex=1|IndexInSheet=5|OwnerPartId=-1|LineWidth=1|LocationCount=2|X1=1679|X1_Frac=42446|Y1=117|Y1_Frac=96838|X2=1576|Y2=118
|RECORD=4|OwnerIndex=1|IndexInSheet=6|OwnerPartId=-1|Location.X=1659|Location.Y=27|Justification=4|Color=16711680|FontID=5|Text==SheetTotal
|RECORD=30|OwnerIndex=1|IndexInSheet=7|OwnerPartId=-1|Location.X=1578|Location.Y=65|Corner.X=1673|Corner.X_Frac=88801|Corner.Y=115|KeepAspect=T|FileName=C:\Users\<user>\Desktop\Timecard Logo\TIMECARD.jpg
|RECORD=6|OwnerIndex=1|IndexInSheet=8|OwnerPartId=-1|LineWidth=1|LocationCount=2|X1=1576|X1_Frac=3162|Y1=117|Y1_Frac=42446|X2=1576|Y2=21
|RECORD=6|OwnerIndex=1|IndexInSheet=9|OwnerPartId=-1|LocationCount=2|X1=1680|Y1=51|X2=1576|Y2=51
|RECORD=4|OwnerIndex=1|IndexInSheet=10|OwnerPartId=-1|Location.X=1581|Location.X_Frac=42446|Location.Y=56|Location.Y_Frac=96838|Justification=3|FontID=2|Text=REV
|RECORD=4|OwnerIndex=1|IndexInSheet=11|OwnerPartId=-1|Location.X=1619|Location.Y=57|Justification=3|FontID=2|Text=DATE
|RECORD=6|OwnerIndex=1|IndexInSheet=12|OwnerPartId=-1|LocationCount=2|X1=1680|Y1=65|X2=1576|Y2=65
|RECORD=4|OwnerIndex=1|IndexInSheet=13|OwnerPartId=-1|Location.X=1605|Location.Y=58|Justification=4|Color=16711680|FontID=5|Text==ProjectRevision
|RECORD=4|OwnerIndex=1|IndexInSheet=14|OwnerPartId=-1|Location.X=1659|Location.Y=58|Justification=4|Color=16711680|FontID=5|Text==ProjectDate
|RECORD=41|IndexInSheet=1|OwnerPartId=-1|Location.X=21474|Location.X_Frac=83647|Location.Y=21464|Location.Y_Frac=83647|Color=8388608|FontID=1|IsHidden=T|Text=01910|Name=Customer
|RECORD=41|IndexInSheet=2|OwnerPartId=-1|Location.X=1000|Location.Y=10|Color=8388608|FontID=1|IsHidden=T|Text=*|Name=DocStatus
|RECORD=17|IndexInSheet=3|OwnerPartId=-1|ShowNetName=T|Location.X=410|Location.Y=1008|Orientation=1|Color=128|FontID=1|Text=+5.0V
|RECORD=22|IndexInSheet=4|OwnerPartId=-1|Location.X=460|Location.Y=938|Color=255|Orientation=1|Symbol=Thin Cross|IsActive=T|SuppressAll=T
|RECORD=22|IndexInSheet=5|OwnerPartId=-1|Location.X=460|Location.Y=928|Color=255|Orientation=1|Symbol=Thin Cross|IsActive=T|SuppressAll=T
|RECORD=22|IndexInSheet=6|OwnerPartId=-1|Location.X=460|Location.Y=918|Color=255|Orientation=1|Symbol=Thin Cross|IsActive=T|SuppressAll=T
|RECORD=22|IndexInSheet=7|OwnerPartId=-1|Location.X=460|Location.Y=908|Color=255|Orientation=1|Symbol=Thin Cross|IsActive=T|SuppressAll=T
|RECORD=22|IndexInSheet=8|OwnerPartId=-1|Location.X=460|Location.Y=718|Color=255|Orientation=1|Symbol=Thin Cross|IsActive=T|SuppressAll=T
|RECORD=22|IndexInSheet=9|OwnerPartId=-1|Location.X=460|Location.Y=708|Color=255|Orientation=1|Symbol=Thin Cross|IsActive=T|SuppressAll=T
|RECORD=22|IndexInSheet=10|OwnerPartId=-1|Location.X=460|Location.Y=598|Color=255|Orientation=1|Symbol=Thin Cross|IsActive=T|SuppressAll=T
|RECORD=17|IndexInSheet=11|OwnerPartId=-1|Style=4|ShowNetName=T|Location.X=410|Location.Y=568|Orientation=3|Color=128|FontID=1|Text=GND
|RECORD=17|IndexInSheet=12|OwnerPartId=-1|ShowNetName=T|Location.X=330|Location.Y=658|Orientation=2|Color=255|FontID=1|Text=KEY2|IsCrossSheetConnector=T
|RECORD=17|IndexInSheet=13|OwnerPartId=-1|ShowNetName=T|Location.X=330|Location.Y=638|Orientation=2|Color=255|FontID=1|Text=LED4|IsCrossSheetConnector=T
|RECORD=17|IndexInSheet=14|OwnerPartId=-1|ShowNetName=T|Location.X=330|Location.Y=628|Orientation=2|Color=255|FontID=1|Text=LED3|IsCrossSheetConnector=T
|RECORD=17|IndexInSheet=15|OwnerPartId=-1|ShowNetName=T|Location.X=330|Location.Y=618|Orientation=2|Color=255|FontID=1|Text=LED2|IsCrossSheetConnector=T
|RECORD=17|IndexInSheet=16|OwnerPartId=-1|ShowNetName=T|Location.X=330|Location.Y=608|Orientation=2|Color=255|FontID=1|Text=LED1|IsCrossSheetConnector=T
|RECORD=17|IndexInSheet=17|OwnerPartId=-1|ShowNetName=T|Location.X=600|Location.Y=1008|Orientation=1|Color=128|FontID=1|Text=+5.0V
|RECORD=22|IndexInSheet=18|OwnerPartId=-1|Location.X=580|Location.Y=938|Color=255|Orientation=1|Symbol=Thin Cross|IsActive=T|SuppressAll=T
|RECORD=22|IndexInSheet=19|OwnerPartId=-1|Location.X=580|Location.Y=928|Color=255|Orientation=1|Symbol=Thin Cross|IsActive=T|SuppressAll=T
|RECORD=22|IndexInSheet=20|OwnerPartId=-1|Location.X=580|Location.Y=738|Color=255|Orientation=1|Symbol=Thin Cross|IsActive=T|SuppressAll=T
|RECORD=22|IndexInSheet=21|OwnerPartId=-1|Location.X=580|Location.Y=668|Color=255|Orientation=1|Symbol=Thin Cross|IsActive=T|SuppressAll=T
|RECORD=22|IndexInSheet=22|OwnerPartId=-1|Location.X=580|Location.Y=658|Color=255|Orientation=1|Symbol=Thin Cross|IsActive=T|SuppressAll=T
|RECORD=22|IndexInSheet=23|OwnerPartId=-1|Location.X=580|Location.Y=638|Color=255|Orientation=1|Symbol=Thin Cross|IsActive=T|SuppressAll=T
|RECORD=22|IndexInSheet=24|OwnerPartId=-1|Location.X=580|Location.Y=628|Color=255|Orientation=1|Symbol=Thin Cross|IsActive=T|SuppressAll=T
|RECORD=22|IndexInSheet=25|OwnerPartId=-1|Location.X=580|Location.Y=618|Color=255|Orientation=1|Symbol=Thin Cross|IsActive=T|SuppressAll=T
|RECORD=22|IndexInSheet=26|OwnerPartId=-1|Location.X=580|Location.Y=608|Color=255|Orientation=1|Symbol=Thin Cross|IsActive=T|SuppressAll=T
|RECORD=22|IndexInSheet=27|OwnerPartId=-1|Location.X=580|Location.Y=598|Color=255|Orientation=1|Symbol=Thin Cross|IsActive=T|SuppressAll=T
|RECORD=17|IndexInSheet=28|OwnerPartId=-1|Style=4|ShowNetName=T|Location.X=600|Location.Y=568|Orientation=3|Color=128|FontID=1|Text=GND
|RECORD=17|IndexInSheet=29|OwnerPartId=-1|ShowNetName=T|Location.X=640|Location.Y=888|Color=255|FontID=1|Text=GPS1_RST|IsCrossSheetConnector=T
|RECORD=17|IndexInSheet=30|OwnerPartId=-1|ShowNetName=T|Location.X=640|Location.Y=838|Color=255|FontID=1|Text=GPS1_TP1|IsCrossSheetConnector=T
|RECORD=17|IndexInSheet=31|OwnerPartId=-1|ShowNetName=T|Location.X=640|Location.Y=828|Color=255|FontID=1|Text=GPS1_TP2|IsCrossSheetConnector=T
|RECORD=17|IndexInSheet=32|OwnerPartId=-1|Style=4|ShowNetName=T|Location.X=1130|Location.Y=568|Orientation=3|Color=128|FontID=1|Text=GND
|RECORD=17|IndexInSheet=33|OwnerPartId=-1|ShowNetName=T|Location.X=1060|Location.Y=598|Orientation=2|Color=255|FontID=1|Text=GPS1_RX|IsCrossSheetConnector=T
|RECORD=17|IndexInSheet=34|OwnerPartId=-1|ShowNetName=T|Location.X=1060|Location.Y=818|Orientation=2|Color=255|FontID=1|Text=MAC_ALARM|IsCrossSheetConnector=T
|RECORD=17|IndexInSheet=35|OwnerPartId=-1|ShowNetName=T|Location.X=1060|Location.Y=808|Orientation=2|Color=255|FontID=1|Text=MAC_BITE|IsCrossSheetConnector=T
|RECORD=17|IndexInSheet=36|OwnerPartId=-1|ShowNetName=T|Location.X=1060|Location.Y=758|Orientation=2|Color=255|FontID=1|Text=FPGA_MAC_PPS_IN0-|IsCrossSheetConnector=T
|RECORD=17|IndexInSheet=37|OwnerPartId=-1|ShowNetName=T|Location.X=1060|Location.Y=728|Orientation=2|Color=255|FontID=1|Text=FPGA_MAC_PPS_IN1-|IsCrossSheetConnector=T
|RECORD=17|IndexInSheet=38|OwnerPartId=-1|ShowNetName=T|Location.X=1060|Location.Y=778|Orientation=2|Color=255|FontID=1|Text=FPGA_MAC_PPS_OUT-|IsCrossSheetConnector=T
|RECORD=17|IndexInSheet=39|OwnerPartId=-1|ShowNetName=T|Location.X=1060|Location.Y=938|Orientation=2|Color=255|FontID=1|Text=MAC_RF_OUT|IsCrossSheetConnector=T
|RECORD=17|IndexInSheet=40|OwnerPartId=-1|ShowNetName=T|Location.X=1060|Location.Y=688|Orientation=2|Color=255|FontID=1|Text=SDA|IsCrossSheetConnector=T
|RECORD=17|IndexInSheet=41|OwnerPartId=-1|ShowNetName=T|Location.X=1060|Location.Y=658|Orientation=2|Color=255|FontID=1|Text=SCL|IsCrossSheetConnector=T
|RECORD=17|IndexInSheet=42|OwnerPartId=-1|Style=4|ShowNetName=T|Location.X=1320|Location.Y=568|Orientation=3|Color=128|FontID=1|Text=GND
|RECORD=17|IndexInSheet=43|OwnerPartId=-1|ShowNetName=T|Location.X=1350|Location.Y=598|Color=255|FontID=1|Text=GPS1_TX|IsCrossSheetConnector=T
|RECORD=17|IndexInSheet=44|OwnerPartId=-1|ShowNetName=T|Location.X=1350|Location.Y=858|Color=255|FontID=1|Text=MAC_FPGA_UART_RX|IsCrossSheetConnector=T
|RECORD=17|IndexInSheet=45|OwnerPartId=-1|ShowNetName=T|Location.X=1350|Location.Y=868|Color=255|FontID=1|Text=FPGA_MAC_UART_TX|IsCrossSheetConnector=T
|RECORD=17|IndexInSheet=46|OwnerPartId=-1|ShowNetName=T|Location.X=1350|Location.Y=638|Color=255|FontID=1|Text=MAC_USB+|IsCrossSheetConnector=T
|RECORD=17|IndexInSheet=47|OwnerPartId=-1|ShowNetName=T|Location.X=1350|Location.Y=628|Color=255|FontID=1|Text=MAC_USB-|IsCrossSheetConnector=T
|RECORD=17|IndexInSheet=48|OwnerPartId=-1|ShowNetName=T|Location.X=1350|Location.Y=958|Color=255|FontID=1|Text=MAC_USB_PWR|IsCrossSheetConnector=T
|RECORD=17|IndexInSheet=49|OwnerPartId=-1|Style=4|ShowNetName=T|Location.X=400|Location.Y=68|Orientation=3|Color=128|FontID=1|Text=GND
|RECORD=22|IndexInSheet=50|OwnerPartId=-1|Location.X=460|Location.Y=128|Color=255|Orientation=1|Symbol=Thin Cross|IsActive=T|SuppressAll=T
|RECORD=17|IndexInSheet=51|OwnerPartId=-1|ShowNetName=T|Location.X=320|Location.Y=398|Orientation=2|Color=255|FontID=1|Text=PCIE_PERST|IsCrossSheetConnector=T
|RECORD=17|IndexInSheet=52|OwnerPartId=-1|ShowNetName=T|Location.X=320|Location.Y=388|Orientation=2|Color=255|FontID=1|Text=KEY1|IsCrossSheetConnector=T
|RECORD=17|IndexInSheet=53|OwnerPartId=-1|ShowNetName=T|Location.X=320|Location.Y=118|Orientation=2|Color=255|FontID=1|Text=FPGA_TCK|IsCrossSheetConnector=T
|RECORD=17|IndexInSheet=54|OwnerPartId=-1|ShowNetName=T|Location.X=320|Location.Y=108|Orientation=2|Color=255|FontID=1|Text=FPGA_TDO|IsCrossSheetConnector=T
|RECORD=17|IndexInSheet=55|OwnerPartId=-1|Style=4|ShowNetName=T|Location.X=620|Location.Y=68|Orientation=3|Color=128|FontID=1|Text=GND
|RECORD=22|IndexInSheet=56|OwnerPartId=-1|Location.X=580|Location.Y=128|Color=255|Orientation=1|Symbol=Thin Cross|IsActive=T|SuppressAll=T
|RECORD=17|IndexInSheet=57|OwnerPartId=-1|ShowNetName=T|Location.X=690|Location.Y=118|Color=255|FontID=1|Text=FPGA_TDI|IsCrossSheetConnector=T
|RECORD=17|IndexInSheet=58|OwnerPartId=-1|ShowNetName=T|Location.X=690|Location.Y=108|Color=255|FontID=1|Text=FPGA_TMS|IsCrossSheetConnector=T
|RECORD=22|IndexInSheet=59|OwnerPartId=-1|Location.X=1160|Location.Y=498|Color=255|Orientation=1|Symbol=Thin Cross|IsActive=T|SuppressAll=T
|RECORD=22|IndexInSheet=60|OwnerPartId=-1|Location.X=1160|Location.Y=488|Color=255|Orientation=1|Symbol=Thin Cross|IsActive=T|SuppressAll=T
|RECORD=22|IndexInSheet=61|OwnerPartId=-1|Location.X=1160|Location.Y=478|Color=255|Orientation=1|Symbol=Thin Cross|IsActive=T|SuppressAll=T
|RECORD=22|IndexInSheet=62|OwnerPartId=-1|Location.X=1160|Location.Y=468|Color=255|Orientation=1|Symbol=Thin Cross|IsActive=T|SuppressAll=T
|RECORD=22|IndexInSheet=63|OwnerPartId=-1|Location.X=1160|Location.Y=448|Color=255|Orientation=1|Symbol=Thin Cross|IsActive=T|SuppressAll=T
|RECORD=22|IndexInSheet=64|OwnerPartId=-1|Location.X=1160|Location.Y=438|Color=255|Orientation=1|Symbol=Thin Cross|IsActive=T|SuppressAll=T
|RECORD=22|IndexInSheet=65|OwnerPartId=-1|Location.X=1160|Location.Y=108|Color=255|Orientation=1|Symbol=Thin Cross|IsActive=T|SuppressAll=T
|RECORD=17|IndexInSheet=66|OwnerPartId=-1|Style=4|ShowNetName=T|Location.X=1110|Location.Y=78|Orientation=3|Color=128|FontID=1|Text=GND
|RECORD=17|IndexInSheet=67|OwnerPartId=-1|ShowNetName=T|Location.X=1060|Location.Y=418|Orientation=2|Color=255|FontID=1|Text=PCIE_TX3_P|IsCrossSheetConnector=T
|RECORD=17|IndexInSheet=68|OwnerPartId=-1|ShowNetName=T|Location.X=1060|Location.Y=408|Orientation=2|Color=255|FontID=1|Text=PCIE_TX3_N|IsCrossSheetConnector=T
|RECORD=17|IndexInSheet=69|OwnerPartId=-1|ShowNetName=T|Location.X=1060|Location.Y=388|Orientation=2|Color=255|FontID=1|Text=PCIE_RX3_P|IsCrossSheetConnector=T
|RECORD=17|IndexInSheet=70|OwnerPartId=-1|ShowNetName=T|Location.X=1060|Location.Y=378|Orientation=2|Color=255|FontID=1|Text=PCIE_RX3_N|IsCrossSheetConnector=T
|RECORD=17|IndexInSheet=71|OwnerPartId=-1|ShowNetName=T|Location.X=1060|Location.Y=358|Orientation=2|Color=255|FontID=1|Text=PCIE_TX0_P|IsCrossSheetConnector=T
|RECORD=17|IndexInSheet=72|OwnerPartId=-1|ShowNetName=T|Location.X=1060|Location.Y=348|Orientation=2|Color=255|FontID=1|Text=PCIE_TX0_N|IsCrossSheetConnector=T
|RECORD=17|IndexInSheet=73|OwnerPartId=-1|ShowNetName=T|Location.X=1060|Location.Y=328|Orientation=2|Color=255|FontID=1|Text=PCIE_RX0_P|IsCrossSheetConnector=T
|RECORD=17|IndexInSheet=74|OwnerPartId=-1|ShowNetName=T|Location.X=1060|Location.Y=318|Orientation=2|Color=255|FontID=1|Text=PCIE_RX0_N|IsCrossSheetConnector=T
|RECORD=43|IndexInSheet=75|OwnerPartId=-1|Location.X=1070|Location.Y=418|Color=255|Name=DIFFPAIR
|RECORD=41|OwnerIndex=91|OwnerPartId=-1|Location.X=1070|Location.Y=418|Color=8388608|FontID=1|IsHidden=T|Text=True|Name=DifferentialPair
|RECORD=43|IndexInSheet=76|OwnerPartId=-1|Location.X=1070|Location.Y=408|Color=255|Name=DIFFPAIR
|RECORD=41|OwnerIndex=93|OwnerPartId=-1|Location.X=1070|Location.Y=408|Color=8388608|FontID=1|IsHidden=T|Text=True|Name=DifferentialPair
|RECORD=43|IndexInSheet=77|OwnerPartId=-1|Location.X=1070|Location.Y=388|Color=255|Name=DIFFPAIR
|RECORD=41|OwnerIndex=95|OwnerPartId=-1|Location.X=1070|Location.Y=388|Color=8388608|FontID=1|IsHidden=T|Text=True|Name=DifferentialPair
|RECORD=43|IndexInSheet=78|OwnerPartId=-1|Location.X=1070|Location.Y=378|Color=255|Name=DIFFPAIR
|RECORD=41|OwnerIndex=97|OwnerPartId=-1|Location.X=1070|Location.Y=378|Color=8388608|FontID=1|IsHidden=T|Text=True|Name=DifferentialPair
|RECORD=43|IndexInSheet=79|OwnerPartId=-1|Location.X=1070|Location.Y=358|Color=255|Name=DIFFPAIR
|RECORD=41|OwnerIndex=99|OwnerPartId=-1|Location.X=1070|Location.Y=358|Color=8388608|FontID=1|IsHidden=T|Text=True|Name=DifferentialPair
|RECORD=43|IndexInSheet=80|OwnerPartId=-1|Location.X=1070|Location.Y=348|Color=255|Name=DIFFPAIR
|RECORD=41|OwnerIndex=101|OwnerPartId=-1|Location.X=1070|Location.Y=348|Color=8388608|FontID=1|IsHidden=T|Text=True|Name=DifferentialPair
|RECORD=43|IndexInSheet=81|OwnerPartId=-1|Location.X=1070|Location.Y=328|Color=255|Name=DIFFPAIR
|RECORD=41|OwnerIndex=103|OwnerPartId=-1|Location.X=1070|Location.Y=328|Color=8388608|FontID=1|IsHidden=T|Text=True|Name=DifferentialPair
|RECORD=43|IndexInSheet=82|OwnerPartId=-1|Location.X=1070|Location.Y=318|Color=255|Name=DIFFPAIR
|RECORD=41|OwnerIndex=105|OwnerPartId=-1|Location.X=1070|Location.Y=318|Color=8388608|FontID=1|IsHidden=T|Text=True|Name=DifferentialPair
|RECORD=22|IndexInSheet=83|OwnerPartId=-1|Location.X=1280|Location.Y=498|Color=255|Orientation=1|Symbol=Thin Cross|IsActive=T|SuppressAll=T
|RECORD=22|IndexInSheet=84|OwnerPartId=-1|Location.X=1280|Location.Y=488|Color=255|Orientation=1|Symbol=Thin Cross|IsActive=T|SuppressAll=T
|RECORD=22|IndexInSheet=85|OwnerPartId=-1|Location.X=1280|Location.Y=478|Color=255|Orientation=1|Symbol=Thin Cross|IsActive=T|SuppressAll=T
|RECORD=22|IndexInSheet=86|OwnerPartId=-1|Location.X=1280|Location.Y=468|Color=255|Orientation=1|Symbol=Thin Cross|IsActive=T|SuppressAll=T
|RECORD=22|IndexInSheet=87|OwnerPartId=-1|Location.X=1280|Location.Y=108|Color=255|Orientation=1|Symbol=Thin Cross|IsActive=T|SuppressAll=T
|RECORD=17|IndexInSheet=88|OwnerPartId=-1|Style=4|ShowNetName=T|Location.X=1310|Location.Y=78|Orientation=3|Color=128|FontID=1|Text=GND
|RECORD=17|IndexInSheet=89|OwnerPartId=-1|ShowNetName=T|Location.X=1360|Location.Y=448|Color=255|FontID=1|Text=PCIE_TX2_P|IsCrossSheetConnector=T
|RECORD=17|IndexInSheet=90|OwnerPartId=-1|ShowNetName=T|Location.X=1360|Location.Y=438|Color=255|FontID=1|Text=PCIE_TX2_N|IsCrossSheetConnector=T
|RECORD=17|IndexInSheet=91|OwnerPartId=-1|ShowNetName=T|Location.X=1360|Location.Y=418|Color=255|FontID=1|Text=PCIE_RX2_P|IsCrossSheetConnector=T
|RECORD=17|IndexInSheet=92|OwnerPartId=-1|ShowNetName=T|Location.X=1360|Location.Y=408|Color=255|FontID=1|Text=PCIE_RX2_N|IsCrossSheetConnector=T
|RECORD=17|IndexInSheet=93|OwnerPartId=-1|ShowNetName=T|Location.X=1360|Location.Y=388|Color=255|FontID=1|Text=PCIE_TX1_P|IsCrossSheetConnector=T
|RECORD=17|IndexInSheet=94|OwnerPartId=-1|ShowNetName=T|Location.X=1360|Location.Y=378|Color=255|FontID=1|Text=PCIE_TX1_N|IsCrossSheetConnector=T
|RECORD=17|IndexInSheet=95|OwnerPartId=-1|ShowNetName=T|Location.X=1360|Location.Y=358|Color=255|FontID=1|Text=PCIE_RX1_P|IsCrossSheetConnector=T
|RECORD=17|IndexInSheet=96|OwnerPartId=-1|ShowNetName=T|Location.X=1360|Location.Y=348|Color=255|FontID=1|Text=PCIE_RX1_N|IsCrossSheetConnector=T
|RECORD=17|IndexInSheet=97|OwnerPartId=-1|ShowNetName=T|Location.X=1360|Location.Y=328|Color=255|FontID=1|Text=PCIE_CLK_P|IsCrossSheetConnector=T
|RECORD=17|IndexInSheet=98|OwnerPartId=-1|ShowNetName=T|Location.X=1360|Location.Y=318|Color=255|FontID=1|Text=PCIE_CLK_N|IsCrossSheetConnector=T
|RECORD=43|IndexInSheet=99|OwnerPartId=-1|Location.X=1330|Location.Y=448|Color=255|Name=DIFFPAIR
|RECORD=41|OwnerIndex=123|OwnerPartId=-1|Location.X=1330|Location.Y=448|Color=8388608|FontID=1|IsHidden=T|Text=True|Name=DifferentialPair
|RECORD=43|IndexInSheet=100|OwnerPartId=-1|Location.X=1330|Location.Y=438|Color=255|Name=DIFFPAIR
|RECORD=41|OwnerIndex=125|OwnerPartId=-1|Location.X=1330|Location.Y=438|Color=8388608|FontID=1|IsHidden=T|Text=True|Name=DifferentialPair
|RECORD=43|IndexInSheet=101|OwnerPartId=-1|Location.X=1330|Location.Y=418|Color=255|Name=DIFFPAIR
|RECORD=41|OwnerIndex=127|OwnerPartId=-1|Location.X=1330|Location.Y=418|Color=8388608|FontID=1|IsHidden=T|Text=True|Name=DifferentialPair
|RECORD=43|IndexInSheet=102|OwnerPartId=-1|Location.X=1330|Location.Y=408|Color=255|Name=DIFFPAIR
|RECORD=41|OwnerIndex=129|OwnerPartId=-1|Location.X=1330|Location.Y=408|Color=8388608|FontID=1|IsHidden=T|Text=True|Name=DifferentialPair
|RECORD=43|IndexInSheet=103|OwnerPartId=-1|Location.X=1330|Location.Y=388|Color=255|Name=DIFFPAIR
|RECORD=41|OwnerIndex=131|OwnerPartId=-1|Location.X=1330|Location.Y=388|Color=8388608|FontID=1|IsHidden=T|Text=True|Name=DifferentialPair
|RECORD=43|IndexInSheet=104|OwnerPartId=-1|Location.X=1330|Location.Y=378|Color=255|Name=DIFFPAIR
|RECORD=41|OwnerIndex=133|OwnerPartId=-1|Location.X=1330|Location.Y=378|Color=8388608|FontID=1|IsHidden=T|Text=True|Name=DifferentialPair
|RECORD=43|IndexInSheet=105|OwnerPartId=-1|Location.X=1330|Location.Y=358|Color=255|Name=DIFFPAIR
|RECORD=41|OwnerIndex=135|OwnerPartId=-1|Location.X=1330|Location.Y=358|Color=8388608|FontID=1|IsHidden=T|Text=True|Name=DifferentialPair
|RECORD=43|IndexInSheet=106|OwnerPartId=-1|Location.X=1330|Location.Y=348|Color=255|Name=DIFFPAIR
|RECORD=41|OwnerIndex=137|OwnerPartId=-1|Location.X=1330|Location.Y=348|Color=8388608|FontID=1|IsHidden=T|Text=True|Name=DifferentialPair
|RECORD=43|IndexInSheet=107|OwnerPartId=-1|Location.X=1330|Location.Y=328|Color=255|Name=DIFFPAIR
|RECORD=41|OwnerIndex=139|OwnerPartId=-1|Location.X=1330|Location.Y=328|Color=8388608|FontID=1|IsHidden=T|Text=True|Name=DifferentialPair
|RECORD=43|IndexInSheet=108|OwnerPartId=-1|Location.X=1330|Location.Y=318|Color=255|Name=DIFFPAIR
|RECORD=41|OwnerIndex=141|OwnerPartId=-1|Location.X=1330|Location.Y=318|Color=8388608|FontID=1|IsHidden=T|Text=True|Name=DifferentialPair
|RECORD=22|IndexInSheet=109|OwnerPartId=-1|Location.X=460|Location.Y=838|Color=255|Orientation=1|Symbol=Thin Cross|IsActive=T|SuppressAll=T
|RECORD=22|IndexInSheet=110|OwnerPartId=-1|Location.X=460|Location.Y=828|Color=255|Orientation=1|Symbol=Thin Cross|IsActive=T|SuppressAll=T
|RECORD=22|IndexInSheet=111|OwnerPartId=-1|Location.X=460|Location.Y=808|Color=255|Orientation=1|Symbol=Thin Cross|IsActive=T|SuppressAll=T
|RECORD=22|IndexInSheet=112|OwnerPartId=-1|Location.X=460|Location.Y=788|Color=255|Orientation=1|Symbol=Thin Cross|IsActive=T|SuppressAll=T
|RECORD=22|IndexInSheet=113|OwnerPartId=-1|Location.X=460|Location.Y=758|Color=255|Orientation=1|Symbol=Thin Cross|IsActive=T|SuppressAll=T
|RECORD=22|IndexInSheet=114|OwnerPartId=-1|Location.X=460|Location.Y=738|Color=255|Orientation=1|Symbol=Thin Cross|IsActive=T|SuppressAll=T
|RECORD=22|IndexInSheet=115|OwnerPartId=-1|Location.X=460|Location.Y=728|Color=255|Orientation=1|Symbol=Thin Cross|IsActive=T|SuppressAll=T
|RECORD=22|IndexInSheet=116|OwnerPartId=-1|Location.X=460|Location.Y=688|Color=255|Orientation=1|Symbol=Thin Cross|IsActive=T|SuppressAll=T
|RECORD=22|IndexInSheet=117|OwnerPartId=-1|Location.X=460|Location.Y=678|Color=255|Orientation=1|Symbol=Thin Cross|IsActive=T|SuppressAll=T
|RECORD=22|IndexInSheet=118|OwnerPartId=-1|Location.X=460|Location.Y=668|Color=255|Orientation=1|Symbol=Thin Cross|IsActive=T|SuppressAll=T
|RECORD=22|IndexInSheet=119|OwnerPartId=-1|Location.X=460|Location.Y=588|Color=255|Orientation=1|Symbol=Thin Cross|IsActive=T|SuppressAll=T
|RECORD=22|IndexInSheet=120|OwnerPartId=-1|Location.X=460|Location.Y=578|Color=255|Orientation=1|Symbol=Thin Cross|IsActive=T|SuppressAll=T
|RECORD=22|IndexInSheet=121|OwnerPartId=-1|Location.X=580|Location.Y=588|Color=255|Orientation=1|Symbol=Thin Cross|IsActive=T|SuppressAll=T
|RECORD=22|IndexInSheet=122|OwnerPartId=-1|Location.X=580|Location.Y=578|Color=255|Orientation=1|Symbol=Thin Cross|IsActive=T|SuppressAll=T
|RECORD=22|IndexInSheet=123|OwnerPartId=-1|Location.X=580|Location.Y=708|Color=255|Orientation=1|Symbol=Thin Cross|IsActive=T|SuppressAll=T
|RECORD=22|IndexInSheet=124|OwnerPartId=-1|Location.X=580|Location.Y=788|Color=255|Orientation=1|Symbol=Thin Cross|IsActive=T|SuppressAll=T
|RECORD=22|IndexInSheet=125|OwnerPartId=-1|Location.X=580|Location.Y=808|Color=255|Orientation=1|Symbol=Thin Cross|IsActive=T|SuppressAll=T
|RECORD=22|IndexInSheet=126|OwnerPartId=-1|Location.X=580|Location.Y=818|Color=255|Orientation=1|Symbol=Thin Cross|IsActive=T|SuppressAll=T
|RECORD=22|IndexInSheet=127|OwnerPartId=-1|Location.X=580|Location.Y=858|Color=255|Orientation=1|Symbol=Thin Cross|IsActive=T|SuppressAll=T
|RECORD=22|IndexInSheet=128|OwnerPartId=-1|Location.X=580|Location.Y=868|Color=255|Orientation=1|Symbol=Thin Cross|IsActive=T|SuppressAll=T
|RECORD=22|IndexInSheet=129|OwnerPartId=-1|Location.X=580|Location.Y=878|Color=255|Orientation=1|Symbol=Thin Cross|IsActive=T|SuppressAll=T
|RECORD=22|IndexInSheet=130|OwnerPartId=-1|Location.X=580|Location.Y=908|Color=255|Orientation=1|Symbol=Thin Cross|IsActive=T|SuppressAll=T
|RECORD=22|IndexInSheet=131|OwnerPartId=-1|Location.X=580|Location.Y=918|Color=255|Orientation=1|Symbol=Thin Cross|IsActive=T|SuppressAll=T
|RECORD=22|IndexInSheet=132|OwnerPartId=-1|Location.X=1170|Location.Y=958|Color=255|Orientation=1|Symbol=Thin Cross|IsActive=T|SuppressAll=T
|RECORD=22|IndexInSheet=133|OwnerPartId=-1|Location.X=1290|Location.Y=938|Color=255|Orientation=1|Symbol=Thin Cross|IsActive=T|SuppressAll=T
|RECORD=22|IndexInSheet=134|OwnerPartId=-1|Location.X=1290|Location.Y=928|Color=255|Orientation=1|Symbol=Thin Cross|IsActive=T|SuppressAll=T
|RECORD=22|IndexInSheet=135|OwnerPartId=-1|Location.X=1290|Location.Y=888|Color=255|Orientation=1|Symbol=Thin Cross|IsActive=T|SuppressAll=T
|RECORD=22|IndexInSheet=136|OwnerPartId=-1|Location.X=1290|Location.Y=878|Color=255|Orientation=1|Symbol=Thin Cross|IsActive=T|SuppressAll=T
|RECORD=22|IndexInSheet=137|OwnerPartId=-1|Location.X=1290|Location.Y=838|Color=255|Orientation=1|Symbol=Thin Cross|IsActive=T|SuppressAll=T
|RECORD=22|IndexInSheet=138|OwnerPartId=-1|Location.X=1290|Location.Y=788|Color=255|Orientation=1|Symbol=Thin Cross|IsActive=T|SuppressAll=T
|RECORD=22|IndexInSheet=139|OwnerPartId=-1|Location.X=1290|Location.Y=778|Color=255|Orientation=1|Symbol=Thin Cross|IsActive=T|SuppressAll=T
|RECORD=22|IndexInSheet=140|OwnerPartId=-1|Location.X=1290|Location.Y=778|Color=255|Orientation=1|Symbol=Thin Cross|IsActive=T|SuppressAll=T
|RECORD=22|IndexInSheet=141|OwnerPartId=-1|Location.X=1290|Location.Y=768|Color=255|Orientation=1|Symbol=Thin Cross|IsActive=T|SuppressAll=T
|RECORD=22|IndexInSheet=142|OwnerPartId=-1|Location.X=1290|Location.Y=758|Color=255|Orientation=1|Symbol=Thin Cross|IsActive=T|SuppressAll=T
|RECORD=22|IndexInSheet=143|OwnerPartId=-1|Location.X=1290|Location.Y=738|Color=255|Orientation=1|Symbol=Thin Cross|IsActive=T|SuppressAll=T
|RECORD=22|IndexInSheet=144|OwnerPartId=-1|Location.X=1290|Location.Y=728|Color=255|Orientation=1|Symbol=Thin Cross|IsActive=T|SuppressAll=T
|RECORD=22|IndexInSheet=145|OwnerPartId=-1|Location.X=1290|Location.Y=718|Color=255|Orientation=1|Symbol=Thin Cross|IsActive=T|SuppressAll=T
|RECORD=22|IndexInSheet=146|OwnerPartId=-1|Location.X=1290|Location.Y=708|Color=255|Orientation=1|Symbol=Thin Cross|IsActive=T|SuppressAll=T
|RECORD=22|IndexInSheet=147|OwnerPartId=-1|Location.X=1290|Location.Y=688|Color=255|Orientation=1|Symbol=Thin Cross|IsActive=T|SuppressAll=T
|RECORD=22|IndexInSheet=148|OwnerPartId=-1|Location.X=1280|Location.Y=428|Color=255|Orientation=1|Symbol=Thin Cross|IsActive=T|SuppressAll=T
|RECORD=22|IndexInSheet=149|OwnerPartId=-1|Location.X=1280|Location.Y=398|Color=255|Orientation=1|Symbol=Thin Cross|IsActive=T|SuppressAll=T
|RECORD=22|IndexInSheet=150|OwnerPartId=-1|Location.X=1280|Location.Y=368|Color=255|Orientation=1|Symbol=Thin Cross|IsActive=T|SuppressAll=T
|RECORD=22|IndexInSheet=151|OwnerPartId=-1|Location.X=1280|Location.Y=338|Color=255|Orientation=1|Symbol=Thin Cross|IsActive=T|SuppressAll=T
|RECORD=22|IndexInSheet=152|OwnerPartId=-1|Location.X=1280|Location.Y=298|Color=255|Orientation=1|Symbol=Thin Cross|IsActive=T|SuppressAll=T
|RECORD=22|IndexInSheet=153|OwnerPartId=-1|Location.X=1280|Location.Y=288|Color=255|Orientation=1|Symbol=Thin Cross|IsActive=T|SuppressAll=T
|RECORD=22|IndexInSheet=154|OwnerPartId=-1|Location.X=1280|Location.Y=278|Color=255|Orientation=1|Symbol=Thin Cross|IsActive=T|SuppressAll=T
|RECORD=22|IndexInSheet=155|OwnerPartId=-1|Location.X=1280|Location.Y=268|Color=255|Orientation=1|Symbol=Thin Cross|IsActive=T|SuppressAll=T
|RECORD=22|IndexInSheet=156|OwnerPartId=-1|Location.X=1160|Location.Y=298|Color=255|Orientation=1|Symbol=Thin Cross|IsActive=T|SuppressAll=T
|RECORD=22|IndexInSheet=157|OwnerPartId=-1|Location.X=1160|Location.Y=288|Color=255|Orientation=1|Symbol=Thin Cross|IsActive=T|SuppressAll=T
|RECORD=22|IndexInSheet=158|OwnerPartId=-1|Location.X=1160|Location.Y=278|Color=255|Orientation=1|Symbol=Thin Cross|IsActive=T|SuppressAll=T
|RECORD=22|IndexInSheet=159|OwnerPartId=-1|Location.X=1160|Location.Y=268|Color=255|Orientation=1|Symbol=Thin Cross|IsActive=T|SuppressAll=T
|RECORD=22|IndexInSheet=160|OwnerPartId=-1|Location.X=1160|Location.Y=248|Color=255|Orientation=1|Symbol=Thin Cross|IsActive=T|SuppressAll=T
|RECORD=22|IndexInSheet=161|OwnerPartId=-1|Location.X=1160|Location.Y=238|Color=255|Orientation=1|Symbol=Thin Cross|IsActive=T|SuppressAll=T
|RECORD=22|IndexInSheet=162|OwnerPartId=-1|Location.X=1160|Location.Y=228|Color=255|Orientation=1|Symbol=Thin Cross|IsActive=T|SuppressAll=T
|RECORD=22|IndexInSheet=163|OwnerPartId=-1|Location.X=1160|Location.Y=218|Color=255|Orientation=1|Symbol=Thin Cross|IsActive=T|SuppressAll=T
|RECORD=22|IndexInSheet=164|OwnerPartId=-1|Location.X=1280|Location.Y=218|Color=255|Orientation=1|Symbol=Thin Cross|IsActive=T|SuppressAll=T
|RECORD=22|IndexInSheet=165|OwnerPartId=-1|Location.X=1280|Location.Y=228|Color=255|Orientation=1|Symbol=Thin Cross|IsActive=T|SuppressAll=T
|RECORD=22|IndexInSheet=166|OwnerPartId=-1|Location.X=1280|Location.Y=238|Color=255|Orientation=1|Symbol=Thin Cross|IsActive=T|SuppressAll=T
|RECORD=22|IndexInSheet=167|OwnerPartId=-1|Location.X=1280|Location.Y=248|Color=255|Orientation=1|Symbol=Thin Cross|IsActive=T|SuppressAll=T
|RECORD=22|IndexInSheet=168|OwnerPartId=-1|Location.X=1280|Location.Y=198|Color=255|Orientation=1|Symbol=Thin Cross|IsActive=T|SuppressAll=T
|RECORD=22|IndexInSheet=169|OwnerPartId=-1|Location.X=1280|Location.Y=188|Color=255|Orientation=1|Symbol=Thin Cross|IsActive=T|SuppressAll=T
|RECORD=22|IndexInSheet=170|OwnerPartId=-1|Location.X=1280|Location.Y=178|Color=255|Orientation=1|Symbol=Thin Cross|IsActive=T|SuppressAll=T
|RECORD=22|IndexInSheet=171|OwnerPartId=-1|Location.X=1280|Location.Y=168|Color=255|Orientation=1|Symbol=Thin Cross|IsActive=T|SuppressAll=T
|RECORD=22|IndexInSheet=172|OwnerPartId=-1|Location.X=1160|Location.Y=198|Color=255|Orientation=1|Symbol=Thin Cross|IsActive=T|SuppressAll=T
|RECORD=22|IndexInSheet=173|OwnerPartId=-1|Location.X=1160|Location.Y=188|Color=255|Orientation=1|Symbol=Thin Cross|IsActive=T|SuppressAll=T
|RECORD=22|IndexInSheet=174|OwnerPartId=-1|Location.X=1160|Location.Y=178|Color=255|Orientation=1|Symbol=Thin Cross|IsActive=T|SuppressAll=T
|RECORD=22|IndexInSheet=175|OwnerPartId=-1|Location.X=1160|Location.Y=168|Color=255|Orientation=1|Symbol=Thin Cross|IsActive=T|SuppressAll=T
|RECORD=22|IndexInSheet=176|OwnerPartId=-1|Location.X=1160|Location.Y=148|Color=255|Orientation=1|Symbol=Thin Cross|IsActive=T|SuppressAll=T
|RECORD=22|IndexInSheet=177|OwnerPartId=-1|Location.X=1160|Location.Y=138|Color=255|Orientation=1|Symbol=Thin Cross|IsActive=T|SuppressAll=T
|RECORD=22|IndexInSheet=178|OwnerPartId=-1|Location.X=1160|Location.Y=118|Color=255|Orientation=1|Symbol=Thin Cross|IsActive=T|SuppressAll=T
|RECORD=22|IndexInSheet=179|OwnerPartId=-1|Location.X=1160|Location.Y=128|Color=255|Orientation=1|Symbol=Thin Cross|IsActive=T|SuppressAll=T
|RECORD=22|IndexInSheet=180|OwnerPartId=-1|Location.X=1160|Location.Y=98|Color=255|Orientation=1|Symbol=Thin Cross|IsActive=T|SuppressAll=T
|RECORD=22|IndexInSheet=181|OwnerPartId=-1|Location.X=1160|Location.Y=88|Color=255|Orientation=1|Symbol=Thin Cross|IsActive=T|SuppressAll=T
|RECORD=22|IndexInSheet=182|OwnerPartId=-1|Location.X=1280|Location.Y=88|Color=255|Orientation=1|Symbol=Thin Cross|IsActive=T|SuppressAll=T
|RECORD=22|IndexInSheet=183|OwnerPartId=-1|Location.X=1280|Location.Y=98|Color=255|Orientation=1|Symbol=Thin Cross|IsActive=T|SuppressAll=T
|RECORD=22|IndexInSheet=184|OwnerPartId=-1|Location.X=1280|Location.Y=118|Color=255|Orientation=1|Symbol=Thin Cross|IsActive=T|SuppressAll=T
|RECORD=22|IndexInSheet=185|OwnerPartId=-1|Location.X=1280|Location.Y=128|Color=255|Orientation=1|Symbol=Thin Cross|IsActive=T|SuppressAll=T
|RECORD=22|IndexInSheet=186|OwnerPartId=-1|Location.X=1280|Location.Y=138|Color=255|Orientation=1|Symbol=Thin Cross|IsActive=T|SuppressAll=T
|RECORD=22|IndexInSheet=187|OwnerPartId=-1|Location.X=1280|Location.Y=148|Color=255|Orientation=1|Symbol=Thin Cross|IsActive=T|SuppressAll=T
|RECORD=22|IndexInSheet=188|OwnerPartId=-1|Location.X=460|Location.Y=488|Color=255|Orientation=1|Symbol=Thin Cross|IsActive=T|SuppressAll=T
|RECORD=22|IndexInSheet=189|OwnerPartId=-1|Location.X=580|Location.Y=488|Color=255|Orientation=1|Symbol=Thin Cross|IsActive=T|SuppressAll=T
|RECORD=22|IndexInSheet=190|OwnerPartId=-1|Location.X=580|Location.Y=478|Color=255|Orientation=1|Symbol=Thin Cross|IsActive=T|SuppressAll=T
|RECORD=22|IndexInSheet=191|OwnerPartId=-1|Location.X=580|Location.Y=468|Color=255|Orientation=1|Symbol=Thin Cross|IsActive=T|SuppressAll=T
|RECORD=22|IndexInSheet=192|OwnerPartId=-1|Location.X=460|Location.Y=438|Color=255|Orientation=1|Symbol=Thin Cross|IsActive=T|SuppressAll=T
|RECORD=22|IndexInSheet=193|OwnerPartId=-1|Location.X=460|Location.Y=428|Color=255|Orientation=1|Symbol=Thin Cross|IsActive=T|SuppressAll=T
|RECORD=22|IndexInSheet=194|OwnerPartId=-1|Location.X=460|Location.Y=418|Color=255|Orientation=1|Symbol=Thin Cross|IsActive=T|SuppressAll=T
|RECORD=22|IndexInSheet=195|OwnerPartId=-1|Location.X=460|Location.Y=378|Color=255|Orientation=1|Symbol=Thin Cross|IsActive=T|SuppressAll=T
|RECORD=22|IndexInSheet=196|OwnerPartId=-1|Location.X=460|Location.Y=368|Color=255|Orientation=1|Symbol=Thin Cross|IsActive=T|SuppressAll=T
|RECORD=22|IndexInSheet=197|OwnerPartId=-1|Location.X=460|Location.Y=238|Color=255|Orientation=1|Symbol=Thin Cross|IsActive=T|SuppressAll=T
|RECORD=22|IndexInSheet=198|OwnerPartId=-1|Location.X=460|Location.Y=228|Color=255|Orientation=1|Symbol=Thin Cross|IsActive=T|SuppressAll=T
|RECORD=22|IndexInSheet=199|OwnerPartId=-1|Location.X=460|Location.Y=218|Color=255|Orientation=1|Symbol=Thin Cross|IsActive=T|SuppressAll=T
|RECORD=22|IndexInSheet=200|OwnerPartId=-1|Location.X=580|Location.Y=248|Color=255|Orientation=1|Symbol=Thin Cross|IsActive=T|SuppressAll=T
|RECORD=22|IndexInSheet=201|OwnerPartId=-1|Location.X=580|Location.Y=238|Color=255|Orientation=1|Symbol=Thin Cross|IsActive=T|SuppressAll=T
|RECORD=22|IndexInSheet=202|OwnerPartId=-1|Location.X=580|Location.Y=228|Color=255|Orientation=1|Symbol=Thin Cross|IsActive=T|SuppressAll=T
|RECORD=22|IndexInSheet=203|OwnerPartId=-1|Location.X=580|Location.Y=218|Color=255|Orientation=1|Symbol=Thin Cross|IsActive=T|SuppressAll=T
|RECORD=22|IndexInSheet=204|OwnerPartId=-1|Location.X=460|Location.Y=198|Color=255|Orientation=1|Symbol=Thin Cross|IsActive=T|SuppressAll=T
|RECORD=22|IndexInSheet=205|OwnerPartId=-1|Location.X=460|Location.Y=188|Color=255|Orientation=1|Symbol=Thin Cross|IsActive=T|SuppressAll=T
|RECORD=22|IndexInSheet=206|OwnerPartId=-1|Location.X=460|Location.Y=178|Color=255|Orientation=1|Symbol=Thin Cross|IsActive=T|SuppressAll=T
|RECORD=22|IndexInSheet=207|OwnerPartId=-1|Location.X=460|Location.Y=168|Color=255|Orientation=1|Symbol=Thin Cross|IsActive=T|SuppressAll=T
|RECORD=22|IndexInSheet=208|OwnerPartId=-1|Location.X=580|Location.Y=198|Color=255|Orientation=1|Symbol=Thin Cross|IsActive=T|SuppressAll=T
|RECORD=22|IndexInSheet=209|OwnerPartId=-1|Location.X=580|Location.Y=188|Color=255|Orientation=1|Symbol=Thin Cross|IsActive=T|SuppressAll=T
|RECORD=22|IndexInSheet=210|OwnerPartId=-1|Location.X=580|Location.Y=178|Color=255|Orientation=1|Symbol=Thin Cross|IsActive=T|SuppressAll=T
|RECORD=22|IndexInSheet=211|OwnerPartId=-1|Location.X=580|Location.Y=168|Color=255|Orientation=1|Symbol=Thin Cross|IsActive=T|SuppressAll=T
|RECORD=22|IndexInSheet=212|OwnerPartId=-1|Location.X=580|Location.Y=148|Color=255|Orientation=1|Symbol=Thin Cross|IsActive=T|SuppressAll=T
|RECORD=22|IndexInSheet=213|OwnerPartId=-1|Location.X=580|Location.Y=138|Color=255|Orientation=1|Symbol=Thin Cross|IsActive=T|SuppressAll=T
|RECORD=22|IndexInSheet=214|OwnerPartId=-1|Location.X=460|Location.Y=148|Color=255|Orientation=1|Symbol=Thin Cross|IsActive=T|SuppressAll=T
|RECORD=22|IndexInSheet=215|OwnerPartId=-1|Location.X=460|Location.Y=148|Color=255|Orientation=1|Symbol=Thin Cross|IsActive=T|SuppressAll=T
|RECORD=22|IndexInSheet=216|OwnerPartId=-1|Location.X=460|Location.Y=138|Color=255|Orientation=1|Symbol=Thin Cross|IsActive=T|SuppressAll=T
|RECORD=22|IndexInSheet=217|OwnerPartId=-1|Location.X=460|Location.Y=98|Color=255|Orientation=1|Symbol=Thin Cross|IsActive=T|SuppressAll=T
|RECORD=22|IndexInSheet=218|OwnerPartId=-1|Location.X=460|Location.Y=88|Color=255|Orientation=1|Symbol=Thin Cross|IsActive=T|SuppressAll=T
|RECORD=22|IndexInSheet=219|OwnerPartId=-1|Location.X=580|Location.Y=88|Color=255|Orientation=1|Symbol=Thin Cross|IsActive=T|SuppressAll=T
|RECORD=22|IndexInSheet=220|OwnerPartId=-1|Location.X=580|Location.Y=98|Color=255|Orientation=1|Symbol=Thin Cross|IsActive=T|SuppressAll=T
|RECORD=41|IndexInSheet=221|OwnerPartId=-1|Color=8388608|FontID=1|IsHidden=T|Name=ConfigurationParameters|ReadOnlyState=1
|RECORD=41|IndexInSheet=222|OwnerPartId=-1|Color=8388608|FontID=1|IsHidden=T|Name=ConfiguratorName|ReadOnlyState=1
|RECORD=41|IndexInSheet=223|OwnerPartId=-1|Color=8388608|FontID=1|IsHidden=T|Name=VersionControl_RevNumber|ReadOnlyState=1
|RECORD=41|IndexInSheet=224|OwnerPartId=-1|Color=8388608|FontID=1|IsHidden=T|Name=IsUserConfigurable|ReadOnlyState=1
|RECORD=41|IndexInSheet=225|OwnerPartId=-1|Color=8388608|FontID=1|IsHidden=T|Name=VersionControl_ProjFolderRevNumber|ReadOnlyState=1
|RECORD=41|IndexInSheet=226|OwnerPartId=-1|Color=8388608|FontID=1|IsHidden=T|Name=SPICEModelCache|ReadOnlyState=1
|RECORD=22|IndexInSheet=227|OwnerPartId=-1|Location.X=1290|Location.Y=968|Color=255|Orientation=1|Symbol=Thin Cross|IsActive=T|SuppressAll=T
|RECORD=22|IndexInSheet=228|OwnerPartId=-1|Location.X=1170|Location.Y=788|Color=255|Orientation=1|Symbol=Thin Cross|IsActive=T|SuppressAll=T
|RECORD=22|IndexInSheet=229|OwnerPartId=-1|Location.X=1170|Location.Y=768|Color=255|Orientation=1|Symbol=Thin Cross|IsActive=T|SuppressAll=T
|RECORD=22|IndexInSheet=230|OwnerPartId=-1|Location.X=1170|Location.Y=738|Color=255|Orientation=1|Symbol=Thin Cross|IsActive=T|SuppressAll=T
|RECORD=17|IndexInSheet=231|OwnerPartId=-1|ShowNetName=T|Location.X=1061|Location.Y=638|Orientation=2|Color=255|FontID=1|Text=UART1_TXD|IsCrossSheetConnector=T
|RECORD=17|IndexInSheet=232|OwnerPartId=-1|ShowNetName=T|Location.X=1060|Location.Y=608|Orientation=2|Color=255|FontID=1|Text=UART1_RXD|IsCrossSheetConnector=T
|RECORD=17|IndexInSheet=233|OwnerPartId=-1|ShowNetName=T|Location.X=690|Location.Y=448|Color=255|FontID=1|Text=IO_LED1|IsCrossSheetConnector=T
|RECORD=17|IndexInSheet=234|OwnerPartId=-1|ShowNetName=T|Location.X=690|Location.Y=438|Color=255|FontID=1|Text=IO_LED2|IsCrossSheetConnector=T
|RECORD=17|IndexInSheet=235|OwnerPartId=-1|ShowNetName=T|Location.X=690|Location.Y=428|Color=255|FontID=1|Text=IO_LED3|IsCrossSheetConnector=T
|RECORD=17|IndexInSheet=236|OwnerPartId=-1|ShowNetName=T|Location.X=691|Location.Y=418|Color=255|FontID=1|Text=IO_LED4|IsCrossSheetConnector=T
|RECORD=17|IndexInSheet=237|OwnerPartId=-1|ShowNetName=T|Location.X=690|Location.Y=498|Color=255|FontID=1|Text=GPS2_RX_FPGA|IsCrossSheetConnector=T
|RECORD=17|IndexInSheet=238|OwnerPartId=-1|ShowNetName=T|Location.X=318|Location.Y=498|Orientation=2|Color=255|FontID=1|Text=GPS2_TX_FPGA|IsCrossSheetConnector=T
|RECORD=17|IndexInSheet=239|OwnerPartId=-1|ShowNetName=T|Location.X=319|Location.Y=468|Orientation=2|Color=255|FontID=1|Text=GPS2_TP2|IsCrossSheetConnector=T
|RECORD=17|IndexInSheet=240|OwnerPartId=-1|ShowNetName=T|Location.X=319|Location.Y=478|Orientation=2|Color=255|FontID=1|Text=GPS2_TP1|IsCrossSheetConnector=T
|RECORD=17|IndexInSheet=241|OwnerPartId=-1|ShowNetName=T|Location.X=319|Location.Y=448|Orientation=2|Color=255|FontID=1|Text=GPS2_RST|IsCrossSheetConnector=T
|RECORD=22|IndexInSheet=242|OwnerPartId=-1|Location.X=460|Location.Y=888|Color=255|Orientation=1|Symbol=Thin Cross|IsActive=T|SuppressAll=T
|RECORD=22|IndexInSheet=243|OwnerPartId=-1|Location.X=460|Location.Y=878|Color=255|Orientation=1|Symbol=Thin Cross|IsActive=T|SuppressAll=T
|RECORD=22|IndexInSheet=244|OwnerPartId=-1|Location.X=460|Location.Y=868|Color=255|Orientation=1|Symbol=Thin Cross|IsActive=T|SuppressAll=T
|RECORD=22|IndexInSheet=245|OwnerPartId=-1|Location.X=460|Location.Y=858|Color=255|Orientation=1|Symbol=Thin Cross|IsActive=T|SuppressAll=T
|RECORD=22|IndexInSheet=246|OwnerPartId=-1|Location.X=460|Location.Y=818|Color=255|Orientation=1|Symbol=Thin Cross|IsActive=T|SuppressAll=T
|RECORD=22|IndexInSheet=247|OwnerPartId=-1|Location.X=460|Location.Y=778|Color=255|Orientation=1|Symbol=Thin Cross|IsActive=T|SuppressAll=T
|RECORD=22|IndexInSheet=248|OwnerPartId=-1|Location.X=460|Location.Y=768|Color=255|Orientation=1|Symbol=Thin Cross|IsActive=T|SuppressAll=T
|RECORD=22|IndexInSheet=249|OwnerPartId=-1|Location.X=1170|Location.Y=838|Color=255|Orientation=1|Symbol=Thin Cross|IsActive=T|SuppressAll=T
|RECORD=17|IndexInSheet=250|OwnerPartId=-1|ShowNetName=T|Location.X=320|Location.Y=348|Orientation=2|Color=255|FontID=1|Text=ANT1_IO_OUT|IsCrossSheetConnector=T
|RECORD=17|IndexInSheet=251|OwnerPartId=-1|ShowNetName=T|Location.X=320|Location.Y=338|Orientation=2|Color=255|FontID=1|Text=ANT1_IO_IN|IsCrossSheetConnector=T
|RECORD=17|IndexInSheet=252|OwnerPartId=-1|ShowNetName=T|Location.X=320|Location.Y=328|Orientation=2|Color=255|FontID=1|Text=ANT2_IO_OUT|IsCrossSheetConnector=T
|RECORD=17|IndexInSheet=253|OwnerPartId=-1|ShowNetName=T|Location.X=320|Location.Y=318|Orientation=2|Color=255|FontID=1|Text=ANT2_IO_IN|IsCrossSheetConnector=T
|RECORD=17|IndexInSheet=254|OwnerPartId=-1|ShowNetName=T|Location.X=320|Location.Y=298|Orientation=2|Color=255|FontID=1|Text=ANT3_IO_OUT|IsCrossSheetConnector=T
|RECORD=17|IndexInSheet=255|OwnerPartId=-1|ShowNetName=T|Location.X=320|Location.Y=288|Orientation=2|Color=255|FontID=1|Text=ANT3_IO_IN|IsCrossSheetConnector=T
|RECORD=17|IndexInSheet=256|OwnerPartId=-1|ShowNetName=T|Location.X=320|Location.Y=278|Orientation=2|Color=255|FontID=1|Text=ANT4_IO_OUT|IsCrossSheetConnector=T
|RECORD=17|IndexInSheet=257|OwnerPartId=-1|ShowNetName=T|Location.X=320|Location.Y=268|Orientation=2|Color=255|FontID=1|Text=ANT4_IO_IN|IsCrossSheetConnector=T
|RECORD=17|IndexInSheet=258|OwnerPartId=-1|ShowNetName=T|Location.X=691|Location.Y=348|Color=255|FontID=1|Text=EXT_GPIO_7|IsCrossSheetConnector=T
|RECORD=17|IndexInSheet=259|OwnerPartId=-1|ShowNetName=T|Location.X=691|Location.Y=338|Color=255|FontID=1|Text=EXT_GPIO_8|IsCrossSheetConnector=T
|RECORD=17|IndexInSheet=260|OwnerPartId=-1|ShowNetName=T|Location.X=691|Location.Y=328|Color=255|FontID=1|Text=EXT_GPIO_9|IsCrossSheetConnector=T
|RECORD=17|IndexInSheet=261|OwnerPartId=-1|ShowNetName=T|Location.X=691|Location.Y=318|Color=255|FontID=1|Text=EXT_GPIO_10|IsCrossSheetConnector=T
|RECORD=41|IndexInSheet=262|OwnerPartId=-1|Color=8388608|FontID=1|IsHidden=T|Text=*|Name=CurrentTime|ReadOnlyState=1
|RECORD=41|IndexInSheet=263|OwnerPartId=-1|Color=8388608|FontID=1|IsHidden=T|Text=*|Name=CurrentDate|ReadOnlyState=1
|RECORD=41|IndexInSheet=264|OwnerPartId=-1|Color=8388608|FontID=1|IsHidden=T|Text=*|Name=Time|ReadOnlyState=1
|RECORD=41|IndexInSheet=265|OwnerPartId=-1|Color=8388608|FontID=1|IsHidden=T|Text=*|Name=Date|ReadOnlyState=1
|RECORD=41|IndexInSheet=266|OwnerPartId=-1|Color=8388608|FontID=1|IsHidden=T|Text=*|Name=DocumentFullPathAndName|ReadOnlyState=1
|RECORD=41|IndexInSheet=267|OwnerPartId=-1|Color=8388608|FontID=1|IsHidden=T|Text=*|Name=DocumentName|ReadOnlyState=1
|RECORD=41|IndexInSheet=268|OwnerPartId=-1|Color=8388608|FontID=1|IsHidden=T|Text=*|Name=ModifiedDate|ReadOnlyState=1
|RECORD=41|IndexInSheet=269|OwnerPartId=-1|Color=8388608|FontID=1|IsHidden=T|Text=*|Name=ApprovedBy|ReadOnlyState=1
|RECORD=41|IndexInSheet=270|OwnerPartId=-1|Color=8388608|FontID=1|IsHidden=T|Text=*|Name=CheckedBy|ReadOnlyState=1
|RECORD=41|IndexInSheet=271|OwnerPartId=-1|Color=8388608|FontID=1|IsHidden=T|Text=*|Name=Author|ReadOnlyState=1
|RECORD=41|IndexInSheet=272|OwnerPartId=-1|Color=8388608|FontID=1|IsHidden=T|Text=*|Name=CompanyName|ReadOnlyState=1
|RECORD=41|IndexInSheet=273|OwnerPartId=-1|Color=8388608|FontID=1|IsHidden=T|Text=*|Name=DrawnBy|ReadOnlyState=1
|RECORD=41|IndexInSheet=274|OwnerPartId=-1|Color=8388608|FontID=1|IsHidden=T|Text=*|Name=Engineer|ReadOnlyState=1
|RECORD=41|IndexInSheet=275|OwnerPartId=-1|Color=8388608|FontID=1|IsHidden=T|Text=*|Name=Organization|ReadOnlyState=1
|RECORD=41|IndexInSheet=276|OwnerPartId=-1|Color=8388608|FontID=1|IsHidden=T|Text=*|Name=Address1|ReadOnlyState=1
|RECORD=41|IndexInSheet=277|OwnerPartId=-1|Color=8388608|FontID=1|IsHidden=T|Text=*|Name=Address2|ReadOnlyState=1
|RECORD=41|IndexInSheet=278|OwnerPartId=-1|Color=8388608|FontID=1|IsHidden=T|Text=*|Name=Address3|ReadOnlyState=1
|RECORD=41|IndexInSheet=279|OwnerPartId=-1|Color=8388608|FontID=1|IsHidden=T|Text=*|Name=Address4|ReadOnlyState=1
|RECORD=41|IndexInSheet=280|OwnerPartId=-1|Color=8388608|FontID=1|IsHidden=T|Text=*|Name=Title|ReadOnlyState=1
|RECORD=41|IndexInSheet=281|OwnerPartId=-1|Color=8388608|FontID=1|IsHidden=T|Text=*|Name=DocumentNumber|ReadOnlyState=1
|RECORD=41|IndexInSheet=282|OwnerPartId=-1|Color=8388608|FontID=1|IsHidden=T|Text=*|Name=Revision|ReadOnlyState=1
|RECORD=41|IndexInSheet=283|OwnerPartId=-1|Color=8388608|FontID=1|IsHidden=T|Text=*|Name=SheetNumber|ReadOnlyState=1
|RECORD=41|IndexInSheet=284|OwnerPartId=-1|Color=8388608|FontID=1|IsHidden=T|Text=*|Name=SheetTotal|ReadOnlyState=1
|RECORD=41|IndexInSheet=285|OwnerPartId=-1|Color=8388608|FontID=1|IsHidden=T|Text=*|Name=Rule|ReadOnlyState=1
|RECORD=41|IndexInSheet=286|OwnerPartId=-1|Color=8388608|FontID=1|IsHidden=T|Text=*|Name=ImagePath|ReadOnlyState=1
|RECORD=41|IndexInSheet=287|OwnerPartId=-1|Color=8388608|FontID=1|IsHidden=T|Text=*|Name=ProjectName|ReadOnlyState=1
|RECORD=41|IndexInSheet=288|OwnerPartId=-1|Color=8388608|FontID=1|IsHidden=T|Text=*|Name=Application_BuildNumber|ReadOnlyState=1
|RECORD=22|IndexInSheet=289|OwnerPartId=-1|Location.X=580|Location.Y=768|Color=255|Orientation=1|Symbol=Thin Cross|IsActive=T|SuppressAll=T
|RECORD=22|IndexInSheet=290|OwnerPartId=-1|Location.X=580|Location.Y=758|Color=255|Orientation=1|Symbol=Thin Cross|IsActive=T|SuppressAll=T
|RECORD=22|IndexInSheet=291|OwnerPartId=-1|Location.X=580|Location.Y=728|Color=255|Orientation=1|Symbol=Thin Cross|IsActive=T|SuppressAll=T
|RECORD=22|IndexInSheet=292|OwnerPartId=-1|Location.X=580|Location.Y=718|Color=255|Orientation=1|Symbol=Thin Cross|IsActive=T|SuppressAll=T
|RECORD=22|IndexInSheet=293|OwnerPartId=-1|Location.X=580|Location.Y=688|Color=255|Orientation=1|Symbol=Thin Cross|IsActive=T|SuppressAll=T
|RECORD=22|IndexInSheet=294|OwnerPartId=-1|Location.X=580|Location.Y=678|Color=255|Orientation=1|Symbol=Thin Cross|IsActive=T|SuppressAll=T
|RECORD=22|IndexInSheet=295|OwnerPartId=-1|Location.X=1290|Location.Y=678|Color=255|Orientation=1|Symbol=Thin Cross|IsActive=T|SuppressAll=T
|RECORD=22|IndexInSheet=296|OwnerPartId=-1|Location.X=1290|Location.Y=828|Color=255|Orientation=1|Symbol=Thin Cross|IsActive=T|SuppressAll=T
|RECORD=22|IndexInSheet=297|OwnerPartId=-1|Location.X=460|Location.Y=248|Color=255|Orientation=1|Symbol=Thin Cross|IsActive=T|SuppressAll=T
|RECORD=17|IndexInSheet=298|OwnerPartId=-1|ShowNetName=T|Location.X=691|Location.Y=298|Color=255|FontID=1|Text=EXT_GPIO_1|IsCrossSheetConnector=T
|RECORD=17|IndexInSheet=299|OwnerPartId=-1|ShowNetName=T|Location.X=691|Location.Y=288|Color=255|FontID=1|Text=EXT_GPIO_2|IsCrossSheetConnector=T
|RECORD=17|IndexInSheet=300|OwnerPartId=-1|ShowNetName=T|Location.X=691|Location.Y=278|Color=255|FontID=1|Text=EXT_GPIO_3|IsCrossSheetConnector=T
|RECORD=17|IndexInSheet=301|OwnerPartId=-1|ShowNetName=T|Location.X=691|Location.Y=268|Color=255|FontID=1|Text=EXT_GPIO_4|IsCrossSheetConnector=T
|RECORD=17|IndexInSheet=302|OwnerPartId=-1|ShowNetName=T|Location.X=1059|Location.Y=918|Orientation=2|Color=255|FontID=1|Text=ANT1_OUT|IsCrossSheetConnector=T
|RECORD=17|IndexInSheet=303|OwnerPartId=-1|ShowNetName=T|Location.X=1059|Location.Y=888|Orientation=2|Color=255|FontID=1|Text=ANT1_IN|IsCrossSheetConnector=T
|RECORD=17|IndexInSheet=304|OwnerPartId=-1|ShowNetName=T|Location.X=1059|Location.Y=908|Orientation=2|Color=255|FontID=1|Text=ANT2_OUT|IsCrossSheetConnector=T
|RECORD=17|IndexInSheet=305|OwnerPartId=-1|ShowNetName=T|Location.X=1059|Location.Y=878|Orientation=2|Color=255|FontID=1|Text=ANT2_IN|IsCrossSheetConnector=T
|RECORD=17|IndexInSheet=306|OwnerPartId=-1|ShowNetName=T|Location.X=1059|Location.Y=868|Orientation=2|Color=255|FontID=1|Text=ANT3_OUT|IsCrossSheetConnector=T
|RECORD=17|IndexInSheet=307|OwnerPartId=-1|ShowNetName=T|Location.X=1352|Location.Y=918|Color=255|FontID=1|Text=ANT3_IN|IsCrossSheetConnector=T
|RECORD=17|IndexInSheet=308|OwnerPartId=-1|ShowNetName=T|Location.X=1059|Location.Y=858|Orientation=2|Color=255|FontID=1|Text=ANT4_OUT|IsCrossSheetConnector=T
|RECORD=17|IndexInSheet=309|OwnerPartId=-1|ShowNetName=T|Location.X=1352|Location.Y=908|Color=255|FontID=1|Text=ANT4_IN|IsCrossSheetConnector=T
|RECORD=17|IndexInSheet=310|OwnerPartId=-1|ShowNetName=T|Location.X=691|Location.Y=778|Color=255|FontID=1|Text=EXT_EEPROM_WP|IsCrossSheetConnector=T
|RECORD=1|LibReference=Single FPGA Conn|PartCount=2|DisplayModeCount=1|IndexInSheet=311|OwnerPartId=-1|Location.X=460|Location.Y=578|CurrentPartId=1|LibraryPath=*|SourceLibraryName=FPGA_CONN.SchLib|TargetFileName=*|AreaColor=11599871|Color=128|PartIDLocked=T|PinsMoveable=T|DesignItemId=Single FPGA Conn|AllPinCount=84
|RECORD=41|OwnerIndex=345|OwnerPartId=-1|Location.X=455|Location.Y=998|Color=8388608|FontID=1|IsHidden=T|Text=Digi-Key|Name=Supplier 1|ReadOnlyState=3
|RECORD=41|OwnerIndex=345|IndexInSheet=1|OwnerPartId=-1|Location.X=490|Location.Y=998|Color=8388608|FontID=1|IsHidden=T|Text=255-3246-1-ND|Name=Supplier Part Number 1|ReadOnlyState=3
|RECORD=41|OwnerIndex=345|IndexInSheet=2|OwnerPartId=-1|Location.X=490|Location.Y=548|Color=8388608|FontID=1|Text=AXK680347YG|Name=Part Number
|RECORD=14|OwnerIndex=345|IsNotAccesible=T|IndexInSheet=3|OwnerPartId=1|Location.X=490|Location.Y=568|Corner.X=550|Corner.Y=998|Color=128|AreaColor=11599871|IsSolid=T
|RECORD=2|OwnerIndex=345|OwnerPartId=1|FormalType=1|PinConglomerate=26|PinLength=30|Location.X=490|Location.Y=988|Name=1|Designator=1|PinPropagationDelay=0.000000E+000
|RECORD=2|OwnerIndex=345|OwnerPartId=1|FormalType=1|PinConglomerate=24|PinLength=30|Location.X=550|Location.Y=988|Name=2|Designator=2|PinPropagationDelay=0.000000E+000
|RECORD=2|OwnerIndex=345|OwnerPartId=1|FormalType=1|PinConglomerate=26|PinLength=30|Location.X=490|Location.Y=978|Name=3|Designator=3|PinPropagationDelay=0.000000E+000
|RECORD=2|OwnerIndex=345|OwnerPartId=1|FormalType=1|PinConglomerate=24|PinLength=30|Location.X=550|Location.Y=978|Name=4|Designator=4|PinPropagationDelay=0.000000E+000
|RECORD=2|OwnerIndex=345|OwnerPartId=1|FormalType=1|PinConglomerate=26|PinLength=30|Location.X=490|Location.Y=968|Name=5|Designator=5|PinPropagationDelay=0.000000E+000
|RECORD=2|OwnerIndex=345|OwnerPartId=1|FormalType=1|PinConglomerate=24|PinLength=30|Location.X=550|Location.Y=968|Name=6|Designator=6|PinPropagationDelay=0.000000E+000
|RECORD=2|OwnerIndex=345|OwnerPartId=1|FormalType=1|PinConglomerate=26|PinLength=30|Location.X=490|Location.Y=958|Name=7|Designator=7|PinPropagationDelay=0.000000E+000
|RECORD=2|OwnerIndex=345|OwnerPartId=1|FormalType=1|PinConglomerate=24|PinLength=30|Location.X=550|Location.Y=958|Name=8|Designator=8|PinPropagationDelay=0.000000E+000
|RECORD=2|OwnerIndex=345|OwnerPartId=1|FormalType=1|PinConglomerate=26|PinLength=30|Location.X=490|Location.Y=948|Name=9|Designator=9|PinPropagationDelay=0.000000E+000
|RECORD=2|OwnerIndex=345|OwnerPartId=1|FormalType=1|PinConglomerate=24|PinLength=30|Location.X=550|Location.Y=948|Name=10|Designator=10|PinPropagationDelay=0.000000E+000
|RECORD=2|OwnerIndex=345|OwnerPartId=1|FormalType=1|PinConglomerate=26|PinLength=30|Location.X=490|Location.Y=938|Name=11|Designator=11|PinPropagationDelay=0.000000E+000
|RECORD=2|OwnerIndex=345|OwnerPartId=1|FormalType=1|PinConglomerate=24|PinLength=30|Location.X=550|Location.Y=938|Name=12|Designator=12|PinPropagationDelay=0.000000E+000
|RECORD=2|OwnerIndex=345|OwnerPartId=1|FormalType=1|PinConglomerate=26|PinLength=30|Location.X=490|Location.Y=928|Name=13|Designator=13|PinPropagationDelay=0.000000E+000
|RECORD=2|OwnerIndex=345|OwnerPartId=1|FormalType=1|PinConglomerate=24|PinLength=30|Location.X=550|Location.Y=928|Name=14|Designator=14|PinPropagationDelay=0.000000E+000
|RECORD=2|OwnerIndex=345|OwnerPartId=1|FormalType=1|PinConglomerate=26|PinLength=30|Location.X=490|Location.Y=918|Name=15|Designator=15|PinPropagationDelay=0.000000E+000
|RECORD=2|OwnerIndex=345|OwnerPartId=1|FormalType=1|PinConglomerate=24|PinLength=30|Location.X=550|Location.Y=918|Name=16|Designator=16|PinPropagationDelay=0.000000E+000
|RECORD=2|OwnerIndex=345|OwnerPartId=1|FormalType=1|PinConglomerate=26|PinLength=30|Location.X=490|Location.Y=908|Name=17|Designator=17|PinPropagationDelay=0.000000E+000
|RECORD=2|OwnerIndex=345|OwnerPartId=1|FormalType=1|PinConglomerate=24|PinLength=30|Location.X=550|Location.Y=908|Name=18|Designator=18|PinPropagationDelay=0.000000E+000
|RECORD=2|OwnerIndex=345|OwnerPartId=1|FormalType=1|PinConglomerate=26|PinLength=30|Location.X=490|Location.Y=898|Name=19|Designator=19|PinPropagationDelay=0.000000E+000
|RECORD=2|OwnerIndex=345|OwnerPartId=1|FormalType=1|PinConglomerate=24|PinLength=30|Location.X=550|Location.Y=898|Name=20|Designator=20|PinPropagationDelay=0.000000E+000
|RECORD=2|OwnerIndex=345|OwnerPartId=1|FormalType=1|PinConglomerate=26|PinLength=30|Location.X=490|Location.Y=888|Name=21|Designator=21|PinPropagationDelay=0.000000E+000
|RECORD=2|OwnerIndex=345|OwnerPartId=1|FormalType=1|PinConglomerate=24|PinLength=30|Location.X=550|Location.Y=888|Name=22|Designator=22|PinPropagationDelay=0.000000E+000
|RECORD=2|OwnerIndex=345|OwnerPartId=1|FormalType=1|PinConglomerate=26|PinLength=30|Location.X=490|Location.Y=878|Name=23|Designator=23|PinPropagationDelay=0.000000E+000
|RECORD=2|OwnerIndex=345|OwnerPartId=1|FormalType=1|PinConglomerate=24|PinLength=30|Location.X=550|Location.Y=878|Name=24|Designator=24|PinPropagationDelay=0.000000E+000
|RECORD=2|OwnerIndex=345|OwnerPartId=1|FormalType=1|PinConglomerate=26|PinLength=30|Location.X=490|Location.Y=868|Name=25|Designator=25|PinPropagationDelay=0.000000E+000
|RECORD=2|OwnerIndex=345|OwnerPartId=1|FormalType=1|PinConglomerate=24|PinLength=30|Location.X=550|Location.Y=868|Name=26|Designator=26|PinPropagationDelay=0.000000E+000
|RECORD=2|OwnerIndex=345|OwnerPartId=1|FormalType=1|PinConglomerate=26|PinLength=30|Location.X=490|Location.Y=858|Name=27|Designator=27|PinPropagationDelay=0.000000E+000
|RECORD=2|OwnerIndex=345|OwnerPartId=1|FormalType=1|PinConglomerate=24|PinLength=30|Location.X=550|Location.Y=858|Name=28|Designator=28|PinPropagationDelay=0.000000E+000
|RECORD=2|OwnerIndex=345|OwnerPartId=1|FormalType=1|PinConglomerate=26|PinLength=30|Location.X=490|Location.Y=848|Name=29|Designator=29|PinPropagationDelay=0.000000E+000
|RECORD=2|OwnerIndex=345|OwnerPartId=1|FormalType=1|PinConglomerate=24|PinLength=30|Location.X=550|Location.Y=848|Name=30|Designator=30|PinPropagationDelay=0.000000E+000
|RECORD=2|OwnerIndex=345|OwnerPartId=1|FormalType=1|PinConglomerate=26|PinLength=30|Location.X=490|Location.Y=838|Name=31|Designator=31|PinPropagationDelay=0.000000E+000
|RECORD=2|OwnerIndex=345|OwnerPartId=1|FormalType=1|PinConglomerate=24|PinLength=30|Location.X=550|Location.Y=838|Name=32|Designator=32|PinPropagationDelay=0.000000E+000
|RECORD=2|OwnerIndex=345|OwnerPartId=1|FormalType=1|PinConglomerate=26|PinLength=30|Location.X=490|Location.Y=828|Name=33|Designator=33|PinPropagationDelay=0.000000E+000
|RECORD=2|OwnerIndex=345|OwnerPartId=1|FormalType=1|PinConglomerate=24|PinLength=30|Location.X=550|Location.Y=828|Name=34|Designator=34|PinPropagationDelay=0.000000E+000
|RECORD=2|OwnerIndex=345|OwnerPartId=1|FormalType=1|PinConglomerate=26|PinLength=30|Location.X=490|Location.Y=818|Name=35|Designator=35|PinPropagationDelay=0.000000E+000
|RECORD=2|OwnerIndex=345|OwnerPartId=1|FormalType=1|PinConglomerate=24|PinLength=30|Location.X=550|Location.Y=818|Name=36|Designator=36|PinPropagationDelay=0.000000E+000
|RECORD=2|OwnerIndex=345|OwnerPartId=1|FormalType=1|PinConglomerate=26|PinLength=30|Location.X=490|Location.Y=808|Name=37|Designator=37|PinPropagationDelay=0.000000E+000
|RECORD=2|OwnerIndex=345|OwnerPartId=1|FormalType=1|PinConglomerate=24|PinLength=30|Location.X=550|Location.Y=808|Name=38|Designator=38|PinPropagationDelay=0.000000E+000
|RECORD=2|OwnerIndex=345|OwnerPartId=1|FormalType=1|PinConglomerate=26|PinLength=30|Location.X=490|Location.Y=798|Name=39|Designator=39|PinPropagationDelay=0.000000E+000
|RECORD=2|OwnerIndex=345|OwnerPartId=1|FormalType=1|PinConglomerate=24|PinLength=30|Location.X=550|Location.Y=798|Name=40|Designator=40|PinPropagationDelay=0.000000E+000
|RECORD=2|OwnerIndex=345|OwnerPartId=1|FormalType=1|PinConglomerate=26|PinLength=30|Location.X=490|Location.Y=788|Name=41|Designator=41|PinPropagationDelay=0.000000E+000
|RECORD=2|OwnerIndex=345|OwnerPartId=1|FormalType=1|PinConglomerate=24|PinLength=30|Location.X=550|Location.Y=788|Name=42|Designator=42|PinPropagationDelay=0.000000E+000
|RECORD=2|OwnerIndex=345|OwnerPartId=1|FormalType=1|PinConglomerate=26|PinLength=30|Location.X=490|Location.Y=778|Name=43|Designator=43|PinPropagationDelay=0.000000E+000
|RECORD=2|OwnerIndex=345|OwnerPartId=1|FormalType=1|PinConglomerate=24|PinLength=30|Location.X=550|Location.Y=778|Name=44|Designator=44|PinPropagationDelay=0.000000E+000
|RECORD=2|OwnerIndex=345|OwnerPartId=1|FormalType=1|PinConglomerate=26|PinLength=30|Location.X=490|Location.Y=768|Name=45|Designator=45|PinPropagationDelay=0.000000E+000
|RECORD=2|OwnerIndex=345|OwnerPartId=1|FormalType=1|PinConglomerate=24|PinLength=30|Location.X=550|Location.Y=768|Name=46|Designator=46|PinPropagationDelay=0.000000E+000
|RECORD=2|OwnerIndex=345|OwnerPartId=1|FormalType=1|PinConglomerate=26|PinLength=30|Location.X=490|Location.Y=758|Name=47|Designator=47|PinPropagationDelay=0.000000E+000
|RECORD=2|OwnerIndex=345|OwnerPartId=1|FormalType=1|PinConglomerate=24|PinLength=30|Location.X=550|Location.Y=758|Name=48|Designator=48|PinPropagationDelay=0.000000E+000
|RECORD=2|OwnerIndex=345|OwnerPartId=1|FormalType=1|PinConglomerate=26|PinLength=30|Location.X=490|Location.Y=748|Name=49|Designator=49|PinPropagationDelay=0.000000E+000
|RECORD=2|OwnerIndex=345|OwnerPartId=1|FormalType=1|PinConglomerate=24|PinLength=30|Location.X=550|Location.Y=748|Name=50|Designator=50|PinPropagationDelay=0.000000E+000
|RECORD=2|OwnerIndex=345|OwnerPartId=1|FormalType=1|PinConglomerate=26|PinLength=30|Location.X=490|Location.Y=738|Name=51|Designator=51|PinPropagationDelay=0.000000E+000
|RECORD=2|OwnerIndex=345|OwnerPartId=1|FormalType=1|PinConglomerate=24|PinLength=30|Location.X=550|Location.Y=738|Name=52|Designator=52|PinPropagationDelay=0.000000E+000
|RECORD=2|OwnerIndex=345|OwnerPartId=1|FormalType=1|PinConglomerate=26|PinLength=30|Location.X=490|Location.Y=728|Name=53|Designator=53|PinPropagationDelay=0.000000E+000
|RECORD=2|OwnerIndex=345|OwnerPartId=1|FormalType=1|PinConglomerate=24|PinLength=30|Location.X=550|Location.Y=728|Name=54|Designator=54|PinPropagationDelay=0.000000E+000
|RECORD=2|OwnerIndex=345|OwnerPartId=1|FormalType=1|PinConglomerate=26|PinLength=30|Location.X=490|Location.Y=718|Name=55|Designator=55|PinPropagationDelay=0.000000E+000
|RECORD=2|OwnerIndex=345|OwnerPartId=1|FormalType=1|PinConglomerate=24|PinLength=30|Location.X=550|Location.Y=718|Name=56|Designator=56|PinPropagationDelay=0.000000E+000
|RECORD=2|OwnerIndex=345|OwnerPartId=1|FormalType=1|PinConglomerate=26|PinLength=30|Location.X=490|Location.Y=708|Name=57|Designator=57|PinPropagationDelay=0.000000E+000
|RECORD=2|OwnerIndex=345|OwnerPartId=1|FormalType=1|PinConglomerate=24|PinLength=30|Location.X=550|Location.Y=708|Name=58|Designator=58|PinPropagationDelay=0.000000E+000
|RECORD=2|OwnerIndex=345|OwnerPartId=1|FormalType=1|PinConglomerate=26|PinLength=30|Location.X=490|Location.Y=698|Name=59|Designator=59|PinPropagationDelay=0.000000E+000
|RECORD=2|OwnerIndex=345|OwnerPartId=1|FormalType=1|PinConglomerate=24|PinLength=30|Location.X=550|Location.Y=698|Name=60|Designator=60|PinPropagationDelay=0.000000E+000
|RECORD=2|OwnerIndex=345|OwnerPartId=1|FormalType=1|PinConglomerate=26|PinLength=30|Location.X=490|Location.Y=688|Name=61|Designator=61|PinPropagationDelay=0.000000E+000
|RECORD=2|OwnerIndex=345|OwnerPartId=1|FormalType=1|PinConglomerate=24|PinLength=30|Location.X=550|Location.Y=688|Name=62|Designator=62|PinPropagationDelay=0.000000E+000
|RECORD=2|OwnerIndex=345|OwnerPartId=1|FormalType=1|PinConglomerate=26|PinLength=30|Location.X=490|Location.Y=678|Name=63|Designator=63|PinPropagationDelay=0.000000E+000
|RECORD=2|OwnerIndex=345|OwnerPartId=1|FormalType=1|PinConglomerate=24|PinLength=30|Location.X=550|Location.Y=678|Name=64|Designator=64|PinPropagationDelay=0.000000E+000
|RECORD=2|OwnerIndex=345|OwnerPartId=1|FormalType=1|PinConglomerate=26|PinLength=30|Location.X=490|Location.Y=668|Name=65|Designator=65|PinPropagationDelay=0.000000E+000
|RECORD=2|OwnerIndex=345|OwnerPartId=1|FormalType=1|PinConglomerate=24|PinLength=30|Location.X=550|Location.Y=668|Name=66|Designator=66|PinPropagationDelay=0.000000E+000
|RECORD=2|OwnerIndex=345|OwnerPartId=1|FormalType=1|PinConglomerate=26|PinLength=30|Location.X=490|Location.Y=658|Name=67|Designator=67|PinPropagationDelay=0.000000E+000
|RECORD=2|OwnerIndex=345|OwnerPartId=1|FormalType=1|PinConglomerate=24|PinLength=30|Location.X=550|Location.Y=658|Name=68|Designator=68|PinPropagationDelay=0.000000E+000
|RECORD=2|OwnerIndex=345|OwnerPartId=1|FormalType=1|PinConglomerate=26|PinLength=30|Location.X=490|Location.Y=648|Name=69|Designator=69|PinPropagationDelay=0.000000E+000
|RECORD=2|OwnerIndex=345|OwnerPartId=1|FormalType=1|PinConglomerate=24|PinLength=30|Location.X=550|Location.Y=648|Name=70|Designator=70|PinPropagationDelay=0.000000E+000
|RECORD=2|OwnerIndex=345|OwnerPartId=1|FormalType=1|PinConglomerate=26|PinLength=30|Location.X=490|Location.Y=638|Name=71|Designator=71|PinPropagationDelay=0.000000E+000
|RECORD=2|OwnerIndex=345|OwnerPartId=1|FormalType=1|PinConglomerate=24|PinLength=30|Location.X=550|Location.Y=638|Name=72|Designator=72|PinPropagationDelay=0.000000E+000
|RECORD=2|OwnerIndex=345|OwnerPartId=1|FormalType=1|PinConglomerate=26|PinLength=30|Location.X=490|Location.Y=628|Name=73|Designator=73|PinPropagationDelay=0.000000E+000
|RECORD=2|OwnerIndex=345|OwnerPartId=1|FormalType=1|PinConglomerate=24|PinLength=30|Location.X=550|Location.Y=628|Name=74|Designator=74|PinPropagationDelay=0.000000E+000
|RECORD=2|OwnerIndex=345|OwnerPartId=1|FormalType=1|PinConglomerate=26|PinLength=30|Location.X=490|Location.Y=618|Name=75|Designator=75|PinPropagationDelay=0.000000E+000
|RECORD=2|OwnerIndex=345|OwnerPartId=1|FormalType=1|PinConglomerate=24|PinLength=30|Location.X=550|Location.Y=618|Name=76|Designator=76|PinPropagationDelay=0.000000E+000
|RECORD=2|OwnerIndex=345|OwnerPartId=1|FormalType=1|PinConglomerate=26|PinLength=30|Location.X=490|Location.Y=608|Name=77|Designator=77|PinPropagationDelay=0.000000E+000
|RECORD=2|OwnerIndex=345|OwnerPartId=1|FormalType=1|PinConglomerate=24|PinLength=30|Location.X=550|Location.Y=608|Name=78|Designator=78|PinPropagationDelay=0.000000E+000
|RECORD=2|OwnerIndex=345|OwnerPartId=1|FormalType=1|PinConglomerate=26|PinLength=30|Location.X=490|Location.Y=598|Name=79|Designator=79|PinPropagationDelay=0.000000E+000
|RECORD=2|OwnerIndex=345|OwnerPartId=1|FormalType=1|PinConglomerate=24|PinLength=30|Location.X=550|Location.Y=598|Name=80|Designator=80|PinPropagationDelay=0.000000E+000
|RECORD=2|OwnerIndex=345|OwnerPartId=1|FormalType=1|PinConglomerate=26|PinLength=30|Location.X=490|Location.Y=588|Name=81|Designator=81|PinPropagationDelay=0.000000E+000
|RECORD=2|OwnerIndex=345|OwnerPartId=1|FormalType=1|PinConglomerate=24|PinLength=30|Location.X=550|Location.Y=588|Name=82|Designator=82|PinPropagationDelay=0.000000E+000
|RECORD=2|OwnerIndex=345|OwnerPartId=1|FormalType=1|PinConglomerate=26|PinLength=30|Location.X=490|Location.Y=578|Name=83|Designator=83|PinPropagationDelay=0.000000E+000
|RECORD=2|OwnerIndex=345|OwnerPartId=1|FormalType=1|PinConglomerate=24|PinLength=30|Location.X=550|Location.Y=578|Name=84|Designator=84|PinPropagationDelay=0.000000E+000
|RECORD=34|OwnerIndex=345|IndexInSheet=-1|OwnerPartId=-1|Location.X=490|Location.Y=998|Color=8388608|FontID=1|Text=J34|Name=Designator|ReadOnlyState=1
|RECORD=41|OwnerIndex=345|IndexInSheet=-1|OwnerPartId=-1|Location.X=490|Location.Y=558|Color=8388608|FontID=1|Text=Single FPGA Conn|Name=Comment
|RECORD=44|OwnerIndex=345
|RECORD=45|OwnerIndex=520|IndexInSheet=-1|ModelName=SingleFPGAConn|ModelType=PCBLIB|DatafileCount=1|ModelDatafileEntity0=SingleFPGAConn|ModelDatafileKind0=PCBLib|IsCurrent=T
|RECORD=46|OwnerIndex=521
|RECORD=48|OwnerIndex=521
|RECORD=1|LibReference=Single FPGA Conn|PartCount=2|DisplayModeCount=1|IndexInSheet=312|OwnerPartId=-1|Location.X=460|Location.Y=88|CurrentPartId=1|LibraryPath=*|SourceLibraryName=FPGA_CONN.SchLib|TargetFileName=*|AreaColor=11599871|Color=128|PartIDLocked=T|PinsMoveable=T|DesignItemId=Single FPGA Conn|AllPinCount=84
|RECORD=41|OwnerIndex=524|OwnerPartId=-1|Location.X=455|Location.Y=508|Color=8388608|FontID=1|IsHidden=T|Text=Digi-Key|Name=Supplier 1|ReadOnlyState=3
|RECORD=41|OwnerIndex=524|IndexInSheet=1|OwnerPartId=-1|Location.X=490|Location.Y=508|Color=8388608|FontID=1|IsHidden=T|Text=255-3246-1-ND|Name=Supplier Part Number 1|ReadOnlyState=3
|RECORD=41|OwnerIndex=524|IndexInSheet=2|OwnerPartId=-1|Location.X=490|Location.Y=58|Color=8388608|FontID=1|Text=AXK680347YG|Name=Part Number
|RECORD=14|OwnerIndex=524|IsNotAccesible=T|IndexInSheet=3|OwnerPartId=1|Location.X=490|Location.Y=78|Corner.X=550|Corner.Y=508|Color=128|AreaColor=11599871|IsSolid=T
|RECORD=2|OwnerIndex=524|OwnerPartId=1|FormalType=1|PinConglomerate=26|PinLength=30|Location.X=490|Location.Y=498|Name=1|Designator=1|PinPropagationDelay=0.000000E+000
|RECORD=2|OwnerIndex=524|OwnerPartId=1|FormalType=1|PinConglomerate=24|PinLength=30|Location.X=550|Location.Y=498|Name=2|Designator=2|PinPropagationDelay=0.000000E+000
|RECORD=2|OwnerIndex=524|OwnerPartId=1|FormalType=1|PinConglomerate=26|PinLength=30|Location.X=490|Location.Y=488|Name=3|Designator=3|PinPropagationDelay=0.000000E+000
|RECORD=2|OwnerIndex=524|OwnerPartId=1|FormalType=1|PinConglomerate=24|PinLength=30|Location.X=550|Location.Y=488|Name=4|Designator=4|PinPropagationDelay=0.000000E+000
|RECORD=2|OwnerIndex=524|OwnerPartId=1|FormalType=1|PinConglomerate=26|PinLength=30|Location.X=490|Location.Y=478|Name=5|Designator=5|PinPropagationDelay=0.000000E+000
|RECORD=2|OwnerIndex=524|OwnerPartId=1|FormalType=1|PinConglomerate=24|PinLength=30|Location.X=550|Location.Y=478|Name=6|Designator=6|PinPropagationDelay=0.000000E+000
|RECORD=2|OwnerIndex=524|OwnerPartId=1|FormalType=1|PinConglomerate=26|PinLength=30|Location.X=490|Location.Y=468|Name=7|Designator=7|PinPropagationDelay=0.000000E+000
|RECORD=2|OwnerIndex=524|OwnerPartId=1|FormalType=1|PinConglomerate=24|PinLength=30|Location.X=550|Location.Y=468|Name=8|Designator=8|PinPropagationDelay=0.000000E+000
|RECORD=2|OwnerIndex=524|OwnerPartId=1|FormalType=1|PinConglomerate=26|PinLength=30|Location.X=490|Location.Y=458|Name=9|Designator=9|PinPropagationDelay=0.000000E+000
|RECORD=2|OwnerIndex=524|OwnerPartId=1|FormalType=1|PinConglomerate=24|PinLength=30|Location.X=550|Location.Y=458|Name=10|Designator=10|PinPropagationDelay=0.000000E+000
|RECORD=2|OwnerIndex=524|OwnerPartId=1|FormalType=1|PinConglomerate=26|PinLength=30|Location.X=490|Location.Y=448|Name=11|Designator=11|PinPropagationDelay=0.000000E+000
|RECORD=2|OwnerIndex=524|OwnerPartId=1|FormalType=1|PinConglomerate=24|PinLength=30|Location.X=550|Location.Y=448|Name=12|Designator=12|PinPropagationDelay=0.000000E+000
|RECORD=2|OwnerIndex=524|OwnerPartId=1|FormalType=1|PinConglomerate=26|PinLength=30|Location.X=490|Location.Y=438|Name=13|Designator=13|PinPropagationDelay=0.000000E+000
|RECORD=2|OwnerIndex=524|OwnerPartId=1|FormalType=1|PinConglomerate=24|PinLength=30|Location.X=550|Location.Y=438|Name=14|Designator=14|PinPropagationDelay=0.000000E+000
|RECORD=2|OwnerIndex=524|OwnerPartId=1|FormalType=1|PinConglomerate=26|PinLength=30|Location.X=490|Location.Y=428|Name=15|Designator=15|PinPropagationDelay=0.000000E+000
|RECORD=2|OwnerIndex=524|OwnerPartId=1|FormalType=1|PinConglomerate=24|PinLength=30|Location.X=550|Location.Y=428|Name=16|Designator=16|PinPropagationDelay=0.000000E+000
|RECORD=2|OwnerIndex=524|OwnerPartId=1|FormalType=1|PinConglomerate=26|PinLength=30|Location.X=490|Location.Y=418|Name=17|Designator=17|PinPropagationDelay=0.000000E+000
|RECORD=2|OwnerIndex=524|OwnerPartId=1|FormalType=1|PinConglomerate=24|PinLength=30|Location.X=550|Location.Y=418|Name=18|Designator=18|PinPropagationDelay=0.000000E+000
|RECORD=2|OwnerIndex=524|OwnerPartId=1|FormalType=1|PinConglomerate=26|PinLength=30|Location.X=490|Location.Y=408|Name=19|Designator=19|PinPropagationDelay=0.000000E+000
|RECORD=2|OwnerIndex=524|OwnerPartId=1|FormalType=1|PinConglomerate=24|PinLength=30|Location.X=550|Location.Y=408|Name=20|Designator=20|PinPropagationDelay=0.000000E+000
|RECORD=2|OwnerIndex=524|OwnerPartId=1|FormalType=1|PinConglomerate=26|PinLength=30|Location.X=490|Location.Y=398|Name=21|Designator=21|PinPropagationDelay=0.000000E+000
|RECORD=2|OwnerIndex=524|OwnerPartId=1|FormalType=1|PinConglomerate=24|PinLength=30|Location.X=550|Location.Y=398|Name=22|Designator=22|PinPropagationDelay=0.000000E+000
|RECORD=2|OwnerIndex=524|OwnerPartId=1|FormalType=1|PinConglomerate=26|PinLength=30|Location.X=490|Location.Y=388|Name=23|Designator=23|PinPropagationDelay=0.000000E+000
|RECORD=2|OwnerIndex=524|OwnerPartId=1|FormalType=1|PinConglomerate=24|PinLength=30|Location.X=550|Location.Y=388|Name=24|Designator=24|PinPropagationDelay=0.000000E+000
|RECORD=2|OwnerIndex=524|OwnerPartId=1|FormalType=1|PinConglomerate=26|PinLength=30|Location.X=490|Location.Y=378|Name=25|Designator=25|PinPropagationDelay=0.000000E+000
|RECORD=2|OwnerIndex=524|OwnerPartId=1|FormalType=1|PinConglomerate=24|PinLength=30|Location.X=550|Location.Y=378|Name=26|Designator=26|PinPropagationDelay=0.000000E+000
|RECORD=2|OwnerIndex=524|OwnerPartId=1|FormalType=1|PinConglomerate=26|PinLength=30|Location.X=490|Location.Y=368|Name=27|Designator=27|PinPropagationDelay=0.000000E+000
|RECORD=2|OwnerIndex=524|OwnerPartId=1|FormalType=1|PinConglomerate=24|PinLength=30|Location.X=550|Location.Y=368|Name=28|Designator=28|PinPropagationDelay=0.000000E+000
|RECORD=2|OwnerIndex=524|OwnerPartId=1|FormalType=1|PinConglomerate=26|PinLength=30|Location.X=490|Location.Y=358|Name=29|Designator=29|PinPropagationDelay=0.000000E+000
|RECORD=2|OwnerIndex=524|OwnerPartId=1|FormalType=1|PinConglomerate=24|PinLength=30|Location.X=550|Location.Y=358|Name=30|Designator=30|PinPropagationDelay=0.000000E+000
|RECORD=2|OwnerIndex=524|OwnerPartId=1|FormalType=1|PinConglomerate=26|PinLength=30|Location.X=490|Location.Y=348|Name=31|Designator=31|PinPropagationDelay=0.000000E+000
|RECORD=2|OwnerIndex=524|OwnerPartId=1|FormalType=1|PinConglomerate=24|PinLength=30|Location.X=550|Location.Y=348|Name=32|Designator=32|PinPropagationDelay=0.000000E+000
|RECORD=2|OwnerIndex=524|OwnerPartId=1|FormalType=1|PinConglomerate=26|PinLength=30|Location.X=490|Location.Y=338|Name=33|Designator=33|PinPropagationDelay=0.000000E+000
|RECORD=2|OwnerIndex=524|OwnerPartId=1|FormalType=1|PinConglomerate=24|PinLength=30|Location.X=550|Location.Y=338|Name=34|Designator=34|PinPropagationDelay=0.000000E+000
|RECORD=2|OwnerIndex=524|OwnerPartId=1|FormalType=1|PinConglomerate=26|PinLength=30|Location.X=490|Location.Y=328|Name=35|Designator=35|PinPropagationDelay=0.000000E+000
|RECORD=2|OwnerIndex=524|OwnerPartId=1|FormalType=1|PinConglomerate=24|PinLength=30|Location.X=550|Location.Y=328|Name=36|Designator=36|PinPropagationDelay=0.000000E+000
|RECORD=2|OwnerIndex=524|OwnerPartId=1|FormalType=1|PinConglomerate=26|PinLength=30|Location.X=490|Location.Y=318|Name=37|Designator=37|PinPropagationDelay=0.000000E+000
|RECORD=2|OwnerIndex=524|OwnerPartId=1|FormalType=1|PinConglomerate=24|PinLength=30|Location.X=550|Location.Y=318|Name=38|Designator=38|PinPropagationDelay=0.000000E+000
|RECORD=2|OwnerIndex=524|OwnerPartId=1|FormalType=1|PinConglomerate=26|PinLength=30|Location.X=490|Location.Y=308|Name=39|Designator=39|PinPropagationDelay=0.000000E+000
|RECORD=2|OwnerIndex=524|OwnerPartId=1|FormalType=1|PinConglomerate=24|PinLength=30|Location.X=550|Location.Y=308|Name=40|Designator=40|PinPropagationDelay=0.000000E+000
|RECORD=2|OwnerIndex=524|OwnerPartId=1|FormalType=1|PinConglomerate=26|PinLength=30|Location.X=490|Location.Y=298|Name=41|Designator=41|PinPropagationDelay=0.000000E+000
|RECORD=2|OwnerIndex=524|OwnerPartId=1|FormalType=1|PinConglomerate=24|PinLength=30|Location.X=550|Location.Y=298|Name=42|Designator=42|PinPropagationDelay=0.000000E+000
|RECORD=2|OwnerIndex=524|OwnerPartId=1|FormalType=1|PinConglomerate=26|PinLength=30|Location.X=490|Location.Y=288|Name=43|Designator=43|PinPropagationDelay=0.000000E+000
|RECORD=2|OwnerIndex=524|OwnerPartId=1|FormalType=1|PinConglomerate=24|PinLength=30|Location.X=550|Location.Y=288|Name=44|Designator=44|PinPropagationDelay=0.000000E+000
|RECORD=2|OwnerIndex=524|OwnerPartId=1|FormalType=1|PinConglomerate=26|PinLength=30|Location.X=490|Location.Y=278|Name=45|Designator=45|PinPropagationDelay=0.000000E+000
|RECORD=2|OwnerIndex=524|OwnerPartId=1|FormalType=1|PinConglomerate=24|PinLength=30|Location.X=550|Location.Y=278|Name=46|Designator=46|PinPropagationDelay=0.000000E+000
|RECORD=2|OwnerIndex=524|OwnerPartId=1|FormalType=1|PinConglomerate=26|PinLength=30|Location.X=490|Location.Y=268|Name=47|Designator=47|PinPropagationDelay=0.000000E+000
|RECORD=2|OwnerIndex=524|OwnerPartId=1|FormalType=1|PinConglomerate=24|PinLength=30|Location.X=550|Location.Y=268|Name=48|Designator=48|PinPropagationDelay=0.000000E+000
|RECORD=2|OwnerIndex=524|OwnerPartId=1|FormalType=1|PinConglomerate=26|PinLength=30|Location.X=490|Location.Y=258|Name=49|Designator=49|PinPropagationDelay=0.000000E+000
|RECORD=2|OwnerIndex=524|OwnerPartId=1|FormalType=1|PinConglomerate=24|PinLength=30|Location.X=550|Location.Y=258|Name=50|Designator=50|PinPropagationDelay=0.000000E+000
|RECORD=2|OwnerIndex=524|OwnerPartId=1|FormalType=1|PinConglomerate=26|PinLength=30|Location.X=490|Location.Y=248|Name=51|Designator=51|PinPropagationDelay=0.000000E+000
|RECORD=2|OwnerIndex=524|OwnerPartId=1|FormalType=1|PinConglomerate=24|PinLength=30|Location.X=550|Location.Y=248|Name=52|Designator=52|PinPropagationDelay=0.000000E+000
|RECORD=2|OwnerIndex=524|OwnerPartId=1|FormalType=1|PinConglomerate=26|PinLength=30|Location.X=490|Location.Y=238|Name=53|Designator=53|PinPropagationDelay=0.000000E+000
|RECORD=2|OwnerIndex=524|OwnerPartId=1|FormalType=1|PinConglomerate=24|PinLength=30|Location.X=550|Location.Y=238|Name=54|Designator=54|PinPropagationDelay=0.000000E+000
|RECORD=2|OwnerIndex=524|OwnerPartId=1|FormalType=1|PinConglomerate=26|PinLength=30|Location.X=490|Location.Y=228|Name=55|Designator=55|PinPropagationDelay=0.000000E+000
|RECORD=2|OwnerIndex=524|OwnerPartId=1|FormalType=1|PinConglomerate=24|PinLength=30|Location.X=550|Location.Y=228|Name=56|Designator=56|PinPropagationDelay=0.000000E+000
|RECORD=2|OwnerIndex=524|OwnerPartId=1|FormalType=1|PinConglomerate=26|PinLength=30|Location.X=490|Location.Y=218|Name=57|Designator=57|PinPropagationDelay=0.000000E+000
|RECORD=2|OwnerIndex=524|OwnerPartId=1|FormalType=1|PinConglomerate=24|PinLength=30|Location.X=550|Location.Y=218|Name=58|Designator=58|PinPropagationDelay=0.000000E+000
|RECORD=2|OwnerIndex=524|OwnerPartId=1|FormalType=1|PinConglomerate=26|PinLength=30|Location.X=490|Location.Y=208|Name=59|Designator=59|PinPropagationDelay=0.000000E+000
|RECORD=2|OwnerIndex=524|OwnerPartId=1|FormalType=1|PinConglomerate=24|PinLength=30|Location.X=550|Location.Y=208|Name=60|Designator=60|PinPropagationDelay=0.000000E+000
|RECORD=2|OwnerIndex=524|OwnerPartId=1|FormalType=1|PinConglomerate=26|PinLength=30|Location.X=490|Location.Y=198|Name=61|Designator=61|PinPropagationDelay=0.000000E+000
|RECORD=2|OwnerIndex=524|OwnerPartId=1|FormalType=1|PinConglomerate=24|PinLength=30|Location.X=550|Location.Y=198|Name=62|Designator=62|PinPropagationDelay=0.000000E+000
|RECORD=2|OwnerIndex=524|OwnerPartId=1|FormalType=1|PinConglomerate=26|PinLength=30|Location.X=490|Location.Y=188|Name=63|Designator=63|PinPropagationDelay=0.000000E+000
|RECORD=2|OwnerIndex=524|OwnerPartId=1|FormalType=1|PinConglomerate=24|PinLength=30|Location.X=550|Location.Y=188|Name=64|Designator=64|PinPropagationDelay=0.000000E+000
|RECORD=2|OwnerIndex=524|OwnerPartId=1|FormalType=1|PinConglomerate=26|PinLength=30|Location.X=490|Location.Y=178|Name=65|Designator=65|PinPropagationDelay=0.000000E+000
|RECORD=2|OwnerIndex=524|OwnerPartId=1|FormalType=1|PinConglomerate=24|PinLength=30|Location.X=550|Location.Y=178|Name=66|Designator=66|PinPropagationDelay=0.000000E+000
|RECORD=2|OwnerIndex=524|OwnerPartId=1|FormalType=1|PinConglomerate=26|PinLength=30|Location.X=490|Location.Y=168|Name=67|Designator=67|PinPropagationDelay=0.000000E+000
|RECORD=2|OwnerIndex=524|OwnerPartId=1|FormalType=1|PinConglomerate=24|PinLength=30|Location.X=550|Location.Y=168|Name=68|Designator=68|PinPropagationDelay=0.000000E+000
|RECORD=2|OwnerIndex=524|OwnerPartId=1|FormalType=1|PinConglomerate=26|PinLength=30|Location.X=490|Location.Y=158|Name=69|Designator=69|PinPropagationDelay=0.000000E+000
|RECORD=2|OwnerIndex=524|OwnerPartId=1|FormalType=1|PinConglomerate=24|PinLength=30|Location.X=550|Location.Y=158|Name=70|Designator=70|PinPropagationDelay=0.000000E+000
|RECORD=2|OwnerIndex=524|OwnerPartId=1|FormalType=1|PinConglomerate=26|PinLength=30|Location.X=490|Location.Y=148|Name=71|Designator=71|PinPropagationDelay=0.000000E+000
|RECORD=2|OwnerIndex=524|OwnerPartId=1|FormalType=1|PinConglomerate=24|PinLength=30|Location.X=550|Location.Y=148|Name=72|Designator=72|PinPropagationDelay=0.000000E+000
|RECORD=2|OwnerIndex=524|OwnerPartId=1|FormalType=1|PinConglomerate=26|PinLength=30|Location.X=490|Location.Y=138|Name=73|Designator=73|PinPropagationDelay=0.000000E+000
|RECORD=2|OwnerIndex=524|OwnerPartId=1|FormalType=1|PinConglomerate=24|PinLength=30|Location.X=550|Location.Y=138|Name=74|Designator=74|PinPropagationDelay=0.000000E+000
|RECORD=2|OwnerIndex=524|OwnerPartId=1|FormalType=1|PinConglomerate=26|PinLength=30|Location.X=490|Location.Y=128|Name=75|Designator=75|PinPropagationDelay=0.000000E+000
|RECORD=2|OwnerIndex=524|OwnerPartId=1|FormalType=1|PinConglomerate=24|PinLength=30|Location.X=550|Location.Y=128|Name=76|Designator=76|PinPropagationDelay=0.000000E+000
|RECORD=2|OwnerIndex=524|OwnerPartId=1|FormalType=1|PinConglomerate=26|PinLength=30|Location.X=490|Location.Y=118|Name=77|Designator=77|PinPropagationDelay=0.000000E+000
|RECORD=2|OwnerIndex=524|OwnerPartId=1|FormalType=1|PinConglomerate=24|PinLength=30|Location.X=550|Location.Y=118|Name=78|Designator=78|PinPropagationDelay=0.000000E+000
|RECORD=2|OwnerIndex=524|OwnerPartId=1|FormalType=1|PinConglomerate=26|PinLength=30|Location.X=490|Location.Y=108|Name=79|Designator=79|PinPropagationDelay=0.000000E+000
|RECORD=2|OwnerIndex=524|OwnerPartId=1|FormalType=1|PinConglomerate=24|PinLength=30|Location.X=550|Location.Y=108|Name=80|Designator=80|PinPropagationDelay=0.000000E+000
|RECORD=2|OwnerIndex=524|OwnerPartId=1|FormalType=1|PinConglomerate=26|PinLength=30|Location.X=490|Location.Y=98|Name=81|Designator=81|PinPropagationDelay=0.000000E+000
|RECORD=2|OwnerIndex=524|OwnerPartId=1|FormalType=1|PinConglomerate=24|PinLength=30|Location.X=550|Location.Y=98|Name=82|Designator=82|PinPropagationDelay=0.000000E+000
|RECORD=2|OwnerIndex=524|OwnerPartId=1|FormalType=1|PinConglomerate=26|PinLength=30|Location.X=490|Location.Y=88|Name=83|Designator=83|PinPropagationDelay=0.000000E+000
|RECORD=2|OwnerIndex=524|OwnerPartId=1|FormalType=1|PinConglomerate=24|PinLength=30|Location.X=550|Location.Y=88|Name=84|Designator=84|PinPropagationDelay=0.000000E+000
|RECORD=34|OwnerIndex=524|IndexInSheet=-1|OwnerPartId=-1|Location.X=490|Location.Y=508|Color=8388608|FontID=1|Text=J36|Name=Designator|ReadOnlyState=1
|RECORD=41|OwnerIndex=524|IndexInSheet=-1|OwnerPartId=-1|Location.X=490|Location.Y=68|Color=8388608|FontID=1|Text=Single FPGA Conn|Name=Comment
|RECORD=44|OwnerIndex=524
|RECORD=45|OwnerIndex=699|IndexInSheet=-1|ModelName=SingleFPGAConn|ModelType=PCBLIB|DatafileCount=1|ModelDatafileEntity0=SingleFPGAConn|ModelDatafileKind0=PCBLib|IsCurrent=T
|RECORD=46|OwnerIndex=700
|RECORD=48|OwnerIndex=700
|RECORD=1|LibReference=Single FPGA Conn|PartCount=2|DisplayModeCount=1|IndexInSheet=313|OwnerPartId=-1|Location.X=1170|Location.Y=578|CurrentPartId=1|LibraryPath=*|SourceLibraryName=FPGA_CONN.SchLib|TargetFileName=*|AreaColor=11599871|Color=128|PartIDLocked=T|PinsMoveable=T|DesignItemId=Single FPGA Conn|AllPinCount=84
|RECORD=41|OwnerIndex=703|OwnerPartId=-1|Location.X=1165|Location.Y=998|Color=8388608|FontID=1|IsHidden=T|Text=Digi-Key|Name=Supplier 1|ReadOnlyState=3
|RECORD=41|OwnerIndex=703|IndexInSheet=1|OwnerPartId=-1|Location.X=1200|Location.Y=998|Color=8388608|FontID=1|IsHidden=T|Text=255-3246-1-ND|Name=Supplier Part Number 1|ReadOnlyState=3
|RECORD=41|OwnerIndex=703|IndexInSheet=2|OwnerPartId=-1|Location.X=1200|Location.Y=548|Color=8388608|FontID=1|Text=AXK680347YG|Name=Part Number
|RECORD=14|OwnerIndex=703|IsNotAccesible=T|IndexInSheet=3|OwnerPartId=1|Location.X=1200|Location.Y=568|Corner.X=1260|Corner.Y=998|Color=128|AreaColor=11599871|IsSolid=T
|RECORD=2|OwnerIndex=703|OwnerPartId=1|FormalType=1|PinConglomerate=26|PinLength=30|Location.X=1200|Location.Y=988|Name=1|Designator=1|PinPropagationDelay=0.000000E+000
|RECORD=2|OwnerIndex=703|OwnerPartId=1|FormalType=1|PinConglomerate=24|PinLength=30|Location.X=1260|Location.Y=988|Name=2|Designator=2|PinPropagationDelay=0.000000E+000
|RECORD=2|OwnerIndex=703|OwnerPartId=1|FormalType=1|PinConglomerate=26|PinLength=30|Location.X=1200|Location.Y=978|Name=3|Designator=3|PinPropagationDelay=0.000000E+000
|RECORD=2|OwnerIndex=703|OwnerPartId=1|FormalType=1|PinConglomerate=24|PinLength=30|Location.X=1260|Location.Y=978|Name=4|Designator=4|PinPropagationDelay=0.000000E+000
|RECORD=2|OwnerIndex=703|OwnerPartId=1|FormalType=1|PinConglomerate=26|PinLength=30|Location.X=1200|Location.Y=968|Name=5|Designator=5|PinPropagationDelay=0.000000E+000
|RECORD=2|OwnerIndex=703|OwnerPartId=1|FormalType=1|PinConglomerate=24|PinLength=30|Location.X=1260|Location.Y=968|Name=6|Designator=6|PinPropagationDelay=0.000000E+000
|RECORD=2|OwnerIndex=703|OwnerPartId=1|FormalType=1|PinConglomerate=26|PinLength=30|Location.X=1200|Location.Y=958|Name=7|Designator=7|PinPropagationDelay=0.000000E+000
|RECORD=2|OwnerIndex=703|OwnerPartId=1|FormalType=1|PinConglomerate=24|PinLength=30|Location.X=1260|Location.Y=958|Name=8|Designator=8|PinPropagationDelay=0.000000E+000
|RECORD=2|OwnerIndex=703|OwnerPartId=1|FormalType=1|PinConglomerate=26|PinLength=30|Location.X=1200|Location.Y=948|Name=9|Designator=9|PinPropagationDelay=0.000000E+000
|RECORD=2|OwnerIndex=703|OwnerPartId=1|FormalType=1|PinConglomerate=24|PinLength=30|Location.X=1260|Location.Y=948|Name=10|Designator=10|PinPropagationDelay=0.000000E+000
|RECORD=2|OwnerIndex=703|OwnerPartId=1|FormalType=1|PinConglomerate=26|PinLength=30|Location.X=1200|Location.Y=938|Name=11|Designator=11|PinPropagationDelay=0.000000E+000
|RECORD=2|OwnerIndex=703|OwnerPartId=1|FormalType=1|PinConglomerate=24|PinLength=30|Location.X=1260|Location.Y=938|Name=12|Designator=12|PinPropagationDelay=0.000000E+000
|RECORD=2|OwnerIndex=703|OwnerPartId=1|FormalType=1|PinConglomerate=26|PinLength=30|Location.X=1200|Location.Y=928|Name=13|Designator=13|PinPropagationDelay=0.000000E+000
|RECORD=2|OwnerIndex=703|OwnerPartId=1|FormalType=1|PinConglomerate=24|PinLength=30|Location.X=1260|Location.Y=928|Name=14|Designator=14|PinPropagationDelay=0.000000E+000
|RECORD=2|OwnerIndex=703|OwnerPartId=1|FormalType=1|PinConglomerate=26|PinLength=30|Location.X=1200|Location.Y=918|Name=15|Designator=15|PinPropagationDelay=0.000000E+000
|RECORD=2|OwnerIndex=703|OwnerPartId=1|FormalType=1|PinConglomerate=24|PinLength=30|Location.X=1260|Location.Y=918|Name=16|Designator=16|PinPropagationDelay=0.000000E+000
|RECORD=2|OwnerIndex=703|OwnerPartId=1|FormalType=1|PinConglomerate=26|PinLength=30|Location.X=1200|Location.Y=908|Name=17|Designator=17|PinPropagationDelay=0.000000E+000
|RECORD=2|OwnerIndex=703|OwnerPartId=1|FormalType=1|PinConglomerate=24|PinLength=30|Location.X=1260|Location.Y=908|Name=18|Designator=18|PinPropagationDelay=0.000000E+000
|RECORD=2|OwnerIndex=703|OwnerPartId=1|FormalType=1|PinConglomerate=26|PinLength=30|Location.X=1200|Location.Y=898|Name=19|Designator=19|PinPropagationDelay=0.000000E+000
|RECORD=2|OwnerIndex=703|OwnerPartId=1|FormalType=1|PinConglomerate=24|PinLength=30|Location.X=1260|Location.Y=898|Name=20|Designator=20|PinPropagationDelay=0.000000E+000
|RECORD=2|OwnerIndex=703|OwnerPartId=1|FormalType=1|PinConglomerate=26|PinLength=30|Location.X=1200|Location.Y=888|Name=21|Designator=21|PinPropagationDelay=0.000000E+000
|RECORD=2|OwnerIndex=703|OwnerPartId=1|FormalType=1|PinConglomerate=24|PinLength=30|Location.X=1260|Location.Y=888|Name=22|Designator=22|PinPropagationDelay=0.000000E+000
|RECORD=2|OwnerIndex=703|OwnerPartId=1|FormalType=1|PinConglomerate=26|PinLength=30|Location.X=1200|Location.Y=878|Name=23|Designator=23|PinPropagationDelay=0.000000E+000
|RECORD=2|OwnerIndex=703|OwnerPartId=1|FormalType=1|PinConglomerate=24|PinLength=30|Location.X=1260|Location.Y=878|Name=24|Designator=24|PinPropagationDelay=0.000000E+000
|RECORD=2|OwnerIndex=703|OwnerPartId=1|FormalType=1|PinConglomerate=26|PinLength=30|Location.X=1200|Location.Y=868|Name=25|Designator=25|PinPropagationDelay=0.000000E+000
|RECORD=2|OwnerIndex=703|OwnerPartId=1|FormalType=1|PinConglomerate=24|PinLength=30|Location.X=1260|Location.Y=868|Name=26|Designator=26|PinPropagationDelay=0.000000E+000
|RECORD=2|OwnerIndex=703|OwnerPartId=1|FormalType=1|PinConglomerate=26|PinLength=30|Location.X=1200|Location.Y=858|Name=27|Designator=27|PinPropagationDelay=0.000000E+000
|RECORD=2|OwnerIndex=703|OwnerPartId=1|FormalType=1|PinConglomerate=24|PinLength=30|Location.X=1260|Location.Y=858|Name=28|Designator=28|PinPropagationDelay=0.000000E+000
|RECORD=2|OwnerIndex=703|OwnerPartId=1|FormalType=1|PinConglomerate=26|PinLength=30|Location.X=1200|Location.Y=848|Name=29|Designator=29|PinPropagationDelay=0.000000E+000
|RECORD=2|OwnerIndex=703|OwnerPartId=1|FormalType=1|PinConglomerate=24|PinLength=30|Location.X=1260|Location.Y=848|Name=30|Designator=30|PinPropagationDelay=0.000000E+000
|RECORD=2|OwnerIndex=703|OwnerPartId=1|FormalType=1|PinConglomerate=26|PinLength=30|Location.X=1200|Location.Y=838|Name=31|Designator=31|PinPropagationDelay=0.000000E+000
|RECORD=2|OwnerIndex=703|OwnerPartId=1|FormalType=1|PinConglomerate=24|PinLength=30|Location.X=1260|Location.Y=838|Name=32|Designator=32|PinPropagationDelay=0.000000E+000
|RECORD=2|OwnerIndex=703|OwnerPartId=1|FormalType=1|PinConglomerate=26|PinLength=30|Location.X=1200|Location.Y=828|Name=33|Designator=33|PinPropagationDelay=0.000000E+000
|RECORD=2|OwnerIndex=703|OwnerPartId=1|FormalType=1|PinConglomerate=24|PinLength=30|Location.X=1260|Location.Y=828|Name=34|Designator=34|PinPropagationDelay=0.000000E+000
|RECORD=2|OwnerIndex=703|OwnerPartId=1|FormalType=1|PinConglomerate=26|PinLength=30|Location.X=1200|Location.Y=818|Name=35|Designator=35|PinPropagationDelay=0.000000E+000
|RECORD=2|OwnerIndex=703|OwnerPartId=1|FormalType=1|PinConglomerate=24|PinLength=30|Location.X=1260|Location.Y=818|Name=36|Designator=36|PinPropagationDelay=0.000000E+000
|RECORD=2|OwnerIndex=703|OwnerPartId=1|FormalType=1|PinConglomerate=26|PinLength=30|Location.X=1200|Location.Y=808|Name=37|Designator=37|PinPropagationDelay=0.000000E+000
|RECORD=2|OwnerIndex=703|OwnerPartId=1|FormalType=1|PinConglomerate=24|PinLength=30|Location.X=1260|Location.Y=808|Name=38|Designator=38|PinPropagationDelay=0.000000E+000
|RECORD=2|OwnerIndex=703|OwnerPartId=1|FormalType=1|PinConglomerate=26|PinLength=30|Location.X=1200|Location.Y=798|Name=39|Designator=39|PinPropagationDelay=0.000000E+000
|RECORD=2|OwnerIndex=703|OwnerPartId=1|FormalType=1|PinConglomerate=24|PinLength=30|Location.X=1260|Location.Y=798|Name=40|Designator=40|PinPropagationDelay=0.000000E+000
|RECORD=2|OwnerIndex=703|OwnerPartId=1|FormalType=1|PinConglomerate=26|PinLength=30|Location.X=1200|Location.Y=788|Name=41|Designator=41|PinPropagationDelay=0.000000E+000
|RECORD=2|OwnerIndex=703|OwnerPartId=1|FormalType=1|PinConglomerate=24|PinLength=30|Location.X=1260|Location.Y=788|Name=42|Designator=42|PinPropagationDelay=0.000000E+000
|RECORD=2|OwnerIndex=703|OwnerPartId=1|FormalType=1|PinConglomerate=26|PinLength=30|Location.X=1200|Location.Y=778|Name=43|Designator=43|PinPropagationDelay=0.000000E+000
|RECORD=2|OwnerIndex=703|OwnerPartId=1|FormalType=1|PinConglomerate=24|PinLength=30|Location.X=1260|Location.Y=778|Name=44|Designator=44|PinPropagationDelay=0.000000E+000
|RECORD=2|OwnerIndex=703|OwnerPartId=1|FormalType=1|PinConglomerate=26|PinLength=30|Location.X=1200|Location.Y=768|Name=45|Designator=45|PinPropagationDelay=0.000000E+000
|RECORD=2|OwnerIndex=703|OwnerPartId=1|FormalType=1|PinConglomerate=24|PinLength=30|Location.X=1260|Location.Y=768|Name=46|Designator=46|PinPropagationDelay=0.000000E+000
|RECORD=2|OwnerIndex=703|OwnerPartId=1|FormalType=1|PinConglomerate=26|PinLength=30|Location.X=1200|Location.Y=758|Name=47|Designator=47|PinPropagationDelay=0.000000E+000
|RECORD=2|OwnerIndex=703|OwnerPartId=1|FormalType=1|PinConglomerate=24|PinLength=30|Location.X=1260|Location.Y=758|Name=48|Designator=48|PinPropagationDelay=0.000000E+000
|RECORD=2|OwnerIndex=703|OwnerPartId=1|FormalType=1|PinConglomerate=26|PinLength=30|Location.X=1200|Location.Y=748|Name=49|Designator=49|PinPropagationDelay=0.000000E+000
|RECORD=2|OwnerIndex=703|OwnerPartId=1|FormalType=1|PinConglomerate=24|PinLength=30|Location.X=1260|Location.Y=748|Name=50|Designator=50|PinPropagationDelay=0.000000E+000
|RECORD=2|OwnerIndex=703|OwnerPartId=1|FormalType=1|PinConglomerate=26|PinLength=30|Location.X=1200|Location.Y=738|Name=51|Designator=51|PinPropagationDelay=0.000000E+000
|RECORD=2|OwnerIndex=703|OwnerPartId=1|FormalType=1|PinConglomerate=24|PinLength=30|Location.X=1260|Location.Y=738|Name=52|Designator=52|PinPropagationDelay=0.000000E+000
|RECORD=2|OwnerIndex=703|OwnerPartId=1|FormalType=1|PinConglomerate=26|PinLength=30|Location.X=1200|Location.Y=728|Name=53|Designator=53|PinPropagationDelay=0.000000E+000
|RECORD=2|OwnerIndex=703|OwnerPartId=1|FormalType=1|PinConglomerate=24|PinLength=30|Location.X=1260|Location.Y=728|Name=54|Designator=54|PinPropagationDelay=0.000000E+000
|RECORD=2|OwnerIndex=703|OwnerPartId=1|FormalType=1|PinConglomerate=26|PinLength=30|Location.X=1200|Location.Y=718|Name=55|Designator=55|PinPropagationDelay=0.000000E+000
|RECORD=2|OwnerIndex=703|OwnerPartId=1|FormalType=1|PinConglomerate=24|PinLength=30|Location.X=1260|Location.Y=718|Name=56|Designator=56|PinPropagationDelay=0.000000E+000
|RECORD=2|OwnerIndex=703|OwnerPartId=1|FormalType=1|PinConglomerate=26|PinLength=30|Location.X=1200|Location.Y=708|Name=57|Designator=57|PinPropagationDelay=0.000000E+000
|RECORD=2|OwnerIndex=703|OwnerPartId=1|FormalType=1|PinConglomerate=24|PinLength=30|Location.X=1260|Location.Y=708|Name=58|Designator=58|PinPropagationDelay=0.000000E+000
|RECORD=2|OwnerIndex=703|OwnerPartId=1|FormalType=1|PinConglomerate=26|PinLength=30|Location.X=1200|Location.Y=698|Name=59|Designator=59|PinPropagationDelay=0.000000E+000
|RECORD=2|OwnerIndex=703|OwnerPartId=1|FormalType=1|PinConglomerate=24|PinLength=30|Location.X=1260|Location.Y=698|Name=60|Designator=60|PinPropagationDelay=0.000000E+000
|RECORD=2|OwnerIndex=703|OwnerPartId=1|FormalType=1|PinConglomerate=26|PinLength=30|Location.X=1200|Location.Y=688|Name=61|Designator=61|PinPropagationDelay=0.000000E+000
|RECORD=2|OwnerIndex=703|OwnerPartId=1|FormalType=1|PinConglomerate=24|PinLength=30|Location.X=1260|Location.Y=688|Name=62|Designator=62|PinPropagationDelay=0.000000E+000
|RECORD=2|OwnerIndex=703|OwnerPartId=1|FormalType=1|PinConglomerate=26|PinLength=30|Location.X=1200|Location.Y=678|Name=63|Designator=63|PinPropagationDelay=0.000000E+000
|RECORD=2|OwnerIndex=703|OwnerPartId=1|FormalType=1|PinConglomerate=24|PinLength=30|Location.X=1260|Location.Y=678|Name=64|Designator=64|PinPropagationDelay=0.000000E+000
|RECORD=2|OwnerIndex=703|OwnerPartId=1|FormalType=1|PinConglomerate=26|PinLength=30|Location.X=1200|Location.Y=668|Name=65|Designator=65|PinPropagationDelay=0.000000E+000
|RECORD=2|OwnerIndex=703|OwnerPartId=1|FormalType=1|PinConglomerate=24|PinLength=30|Location.X=1260|Location.Y=668|Name=66|Designator=66|PinPropagationDelay=0.000000E+000
|RECORD=2|OwnerIndex=703|OwnerPartId=1|FormalType=1|PinConglomerate=26|PinLength=30|Location.X=1200|Location.Y=658|Name=67|Designator=67|PinPropagationDelay=0.000000E+000
|RECORD=2|OwnerIndex=703|OwnerPartId=1|FormalType=1|PinConglomerate=24|PinLength=30|Location.X=1260|Location.Y=658|Name=68|Designator=68|PinPropagationDelay=0.000000E+000
|RECORD=2|OwnerIndex=703|OwnerPartId=1|FormalType=1|PinConglomerate=26|PinLength=30|Location.X=1200|Location.Y=648|Name=69|Designator=69|PinPropagationDelay=0.000000E+000
|RECORD=2|OwnerIndex=703|OwnerPartId=1|FormalType=1|PinConglomerate=24|PinLength=30|Location.X=1260|Location.Y=648|Name=70|Designator=70|PinPropagationDelay=0.000000E+000
|RECORD=2|OwnerIndex=703|OwnerPartId=1|FormalType=1|PinConglomerate=26|PinLength=30|Location.X=1200|Location.Y=638|Name=71|Designator=71|PinPropagationDelay=0.000000E+000
|RECORD=2|OwnerIndex=703|OwnerPartId=1|FormalType=1|PinConglomerate=24|PinLength=30|Location.X=1260|Location.Y=638|Name=72|Designator=72|PinPropagationDelay=0.000000E+000
|RECORD=2|OwnerIndex=703|OwnerPartId=1|FormalType=1|PinConglomerate=26|PinLength=30|Location.X=1200|Location.Y=628|Name=73|Designator=73|PinPropagationDelay=0.000000E+000
|RECORD=2|OwnerIndex=703|OwnerPartId=1|FormalType=1|PinConglomerate=24|PinLength=30|Location.X=1260|Location.Y=628|Name=74|Designator=74|PinPropagationDelay=0.000000E+000
|RECORD=2|OwnerIndex=703|OwnerPartId=1|FormalType=1|PinConglomerate=26|PinLength=30|Location.X=1200|Location.Y=618|Name=75|Designator=75|PinPropagationDelay=0.000000E+000
|RECORD=2|OwnerIndex=703|OwnerPartId=1|FormalType=1|PinConglomerate=24|PinLength=30|Location.X=1260|Location.Y=618|Name=76|Designator=76|PinPropagationDelay=0.000000E+000
|RECORD=2|OwnerIndex=703|OwnerPartId=1|FormalType=1|PinConglomerate=26|PinLength=30|Location.X=1200|Location.Y=608|Name=77|Designator=77|PinPropagationDelay=0.000000E+000
|RECORD=2|OwnerIndex=703|OwnerPartId=1|FormalType=1|PinConglomerate=24|PinLength=30|Location.X=1260|Location.Y=608|Name=78|Designator=78|PinPropagationDelay=0.000000E+000
|RECORD=2|OwnerIndex=703|OwnerPartId=1|FormalType=1|PinConglomerate=26|PinLength=30|Location.X=1200|Location.Y=598|Name=79|Designator=79|PinPropagationDelay=0.000000E+000
|RECORD=2|OwnerIndex=703|OwnerPartId=1|FormalType=1|PinConglomerate=24|PinLength=30|Location.X=1260|Location.Y=598|Name=80|Designator=80|PinPropagationDelay=0.000000E+000
|RECORD=2|OwnerIndex=703|OwnerPartId=1|FormalType=1|PinConglomerate=26|PinLength=30|Location.X=1200|Location.Y=588|Name=81|Designator=81|PinPropagationDelay=0.000000E+000
|RECORD=2|OwnerIndex=703|OwnerPartId=1|FormalType=1|PinConglomerate=24|PinLength=30|Location.X=1260|Location.Y=588|Name=82|Designator=82|PinPropagationDelay=0.000000E+000
|RECORD=2|OwnerIndex=703|OwnerPartId=1|FormalType=1|PinConglomerate=26|PinLength=30|Location.X=1200|Location.Y=578|Name=83|Designator=83|PinPropagationDelay=0.000000E+000
|RECORD=2|OwnerIndex=703|OwnerPartId=1|FormalType=1|PinConglomerate=24|PinLength=30|Location.X=1260|Location.Y=578|Name=84|Designator=84|PinPropagationDelay=0.000000E+000
|RECORD=34|OwnerIndex=703|IndexInSheet=-1|OwnerPartId=-1|Location.X=1200|Location.Y=998|Color=8388608|FontID=1|Text=J35|Name=Designator|ReadOnlyState=1
|RECORD=41|OwnerIndex=703|IndexInSheet=-1|OwnerPartId=-1|Location.X=1200|Location.Y=558|Color=8388608|FontID=1|Text=Single FPGA Conn|Name=Comment
|RECORD=44|OwnerIndex=703
|RECORD=45|OwnerIndex=878|IndexInSheet=-1|ModelName=SingleFPGAConn|ModelType=PCBLIB|DatafileCount=1|ModelDatafileEntity0=SingleFPGAConn|ModelDatafileKind0=PCBLib|IsCurrent=T
|RECORD=46|OwnerIndex=879
|RECORD=48|OwnerIndex=879
|RECORD=1|LibReference=Single FPGA Conn|PartCount=2|DisplayModeCount=1|IndexInSheet=314|OwnerPartId=-1|Location.X=1160|Location.Y=88|CurrentPartId=1|LibraryPath=*|SourceLibraryName=FPGA_CONN.SchLib|TargetFileName=*|AreaColor=11599871|Color=128|PartIDLocked=T|PinsMoveable=T|DesignItemId=Single FPGA Conn|AllPinCount=84
|RECORD=41|OwnerIndex=882|OwnerPartId=-1|Location.X=1155|Location.Y=508|Color=8388608|FontID=1|IsHidden=T|Text=Digi-Key|Name=Supplier 1|ReadOnlyState=3
|RECORD=41|OwnerIndex=882|IndexInSheet=1|OwnerPartId=-1|Location.X=1190|Location.Y=508|Color=8388608|FontID=1|IsHidden=T|Text=255-3246-1-ND|Name=Supplier Part Number 1|ReadOnlyState=3
|RECORD=41|OwnerIndex=882|IndexInSheet=2|OwnerPartId=-1|Location.X=1190|Location.Y=58|Color=8388608|FontID=1|Text=AXK680347YG|Name=Part Number
|RECORD=14|OwnerIndex=882|IsNotAccesible=T|IndexInSheet=3|OwnerPartId=1|Location.X=1190|Location.Y=78|Corner.X=1250|Corner.Y=508|Color=128|AreaColor=11599871|IsSolid=T
|RECORD=2|OwnerIndex=882|OwnerPartId=1|FormalType=1|PinConglomerate=26|PinLength=30|Location.X=1190|Location.Y=498|Name=1|Designator=1|PinPropagationDelay=0.000000E+000
|RECORD=2|OwnerIndex=882|OwnerPartId=1|FormalType=1|PinConglomerate=24|PinLength=30|Location.X=1250|Location.Y=498|Name=2|Designator=2|PinPropagationDelay=0.000000E+000
|RECORD=2|OwnerIndex=882|OwnerPartId=1|FormalType=1|PinConglomerate=26|PinLength=30|Location.X=1190|Location.Y=488|Name=3|Designator=3|PinPropagationDelay=0.000000E+000
|RECORD=2|OwnerIndex=882|OwnerPartId=1|FormalType=1|PinConglomerate=24|PinLength=30|Location.X=1250|Location.Y=488|Name=4|Designator=4|PinPropagationDelay=0.000000E+000
|RECORD=2|OwnerIndex=882|OwnerPartId=1|FormalType=1|PinConglomerate=26|PinLength=30|Location.X=1190|Location.Y=478|Name=5|Designator=5|PinPropagationDelay=0.000000E+000
|RECORD=2|OwnerIndex=882|OwnerPartId=1|FormalType=1|PinConglomerate=24|PinLength=30|Location.X=1250|Location.Y=478|Name=6|Designator=6|PinPropagationDelay=0.000000E+000
|RECORD=2|OwnerIndex=882|OwnerPartId=1|FormalType=1|PinConglomerate=26|PinLength=30|Location.X=1190|Location.Y=468|Name=7|Designator=7|PinPropagationDelay=0.000000E+000
|RECORD=2|OwnerIndex=882|OwnerPartId=1|FormalType=1|PinConglomerate=24|PinLength=30|Location.X=1250|Location.Y=468|Name=8|Designator=8|PinPropagationDelay=0.000000E+000
|RECORD=2|OwnerIndex=882|OwnerPartId=1|FormalType=1|PinConglomerate=26|PinLength=30|Location.X=1190|Location.Y=458|Name=9|Designator=9|PinPropagationDelay=0.000000E+000
|RECORD=2|OwnerIndex=882|OwnerPartId=1|FormalType=1|PinConglomerate=24|PinLength=30|Location.X=1250|Location.Y=458|Name=10|Designator=10|PinPropagationDelay=0.000000E+000
|RECORD=2|OwnerIndex=882|OwnerPartId=1|FormalType=1|PinConglomerate=26|PinLength=30|Location.X=1190|Location.Y=448|Name=11|Designator=11|PinPropagationDelay=0.000000E+000
|RECORD=2|OwnerIndex=882|OwnerPartId=1|FormalType=1|PinConglomerate=24|PinLength=30|Location.X=1250|Location.Y=448|Name=12|Designator=12|PinPropagationDelay=0.000000E+000
|RECORD=2|OwnerIndex=882|OwnerPartId=1|FormalType=1|PinConglomerate=26|PinLength=30|Location.X=1190|Location.Y=438|Name=13|Designator=13|PinPropagationDelay=0.000000E+000
|RECORD=2|OwnerIndex=882|OwnerPartId=1|FormalType=1|PinConglomerate=24|PinLength=30|Location.X=1250|Location.Y=438|Name=14|Designator=14|PinPropagationDelay=0.000000E+000
|RECORD=2|OwnerIndex=882|OwnerPartId=1|FormalType=1|PinConglomerate=26|PinLength=30|Location.X=1190|Location.Y=428|Name=15|Designator=15|PinPropagationDelay=0.000000E+000
|RECORD=2|OwnerIndex=882|OwnerPartId=1|FormalType=1|PinConglomerate=24|PinLength=30|Location.X=1250|Location.Y=428|Name=16|Designator=16|PinPropagationDelay=0.000000E+000
|RECORD=2|OwnerIndex=882|OwnerPartId=1|FormalType=1|PinConglomerate=26|PinLength=30|Location.X=1190|Location.Y=418|Name=17|Designator=17|PinPropagationDelay=0.000000E+000
|RECORD=2|OwnerIndex=882|OwnerPartId=1|FormalType=1|PinConglomerate=24|PinLength=30|Location.X=1250|Location.Y=418|Name=18|Designator=18|PinPropagationDelay=0.000000E+000
|RECORD=2|OwnerIndex=882|OwnerPartId=1|FormalType=1|PinConglomerate=26|PinLength=30|Location.X=1190|Location.Y=408|Name=19|Designator=19|PinPropagationDelay=0.000000E+000
|RECORD=2|OwnerIndex=882|OwnerPartId=1|FormalType=1|PinConglomerate=24|PinLength=30|Location.X=1250|Location.Y=408|Name=20|Designator=20|PinPropagationDelay=0.000000E+000
|RECORD=2|OwnerIndex=882|OwnerPartId=1|FormalType=1|PinConglomerate=26|PinLength=30|Location.X=1190|Location.Y=398|Name=21|Designator=21|PinPropagationDelay=0.000000E+000
|RECORD=2|OwnerIndex=882|OwnerPartId=1|FormalType=1|PinConglomerate=24|PinLength=30|Location.X=1250|Location.Y=398|Name=22|Designator=22|PinPropagationDelay=0.000000E+000
|RECORD=2|OwnerIndex=882|OwnerPartId=1|FormalType=1|PinConglomerate=26|PinLength=30|Location.X=1190|Location.Y=388|Name=23|Designator=23|PinPropagationDelay=0.000000E+000
|RECORD=2|OwnerIndex=882|OwnerPartId=1|FormalType=1|PinConglomerate=24|PinLength=30|Location.X=1250|Location.Y=388|Name=24|Designator=24|PinPropagationDelay=0.000000E+000
|RECORD=2|OwnerIndex=882|OwnerPartId=1|FormalType=1|PinConglomerate=26|PinLength=30|Location.X=1190|Location.Y=378|Name=25|Designator=25|PinPropagationDelay=0.000000E+000
|RECORD=2|OwnerIndex=882|OwnerPartId=1|FormalType=1|PinConglomerate=24|PinLength=30|Location.X=1250|Location.Y=378|Name=26|Designator=26|PinPropagationDelay=0.000000E+000
|RECORD=2|OwnerIndex=882|OwnerPartId=1|FormalType=1|PinConglomerate=26|PinLength=30|Location.X=1190|Location.Y=368|Name=27|Designator=27|PinPropagationDelay=0.000000E+000
|RECORD=2|OwnerIndex=882|OwnerPartId=1|FormalType=1|PinConglomerate=24|PinLength=30|Location.X=1250|Location.Y=368|Name=28|Designator=28|PinPropagationDelay=0.000000E+000
|RECORD=2|OwnerIndex=882|OwnerPartId=1|FormalType=1|PinConglomerate=26|PinLength=30|Location.X=1190|Location.Y=358|Name=29|Designator=29|PinPropagationDelay=0.000000E+000
|RECORD=2|OwnerIndex=882|OwnerPartId=1|FormalType=1|PinConglomerate=24|PinLength=30|Location.X=1250|Location.Y=358|Name=30|Designator=30|PinPropagationDelay=0.000000E+000
|RECORD=2|OwnerIndex=882|OwnerPartId=1|FormalType=1|PinConglomerate=26|PinLength=30|Location.X=1190|Location.Y=348|Name=31|Designator=31|PinPropagationDelay=0.000000E+000
|RECORD=2|OwnerIndex=882|OwnerPartId=1|FormalType=1|PinConglomerate=24|PinLength=30|Location.X=1250|Location.Y=348|Name=32|Designator=32|PinPropagationDelay=0.000000E+000
|RECORD=2|OwnerIndex=882|OwnerPartId=1|FormalType=1|PinConglomerate=26|PinLength=30|Location.X=1190|Location.Y=338|Name=33|Designator=33|PinPropagationDelay=0.000000E+000
|RECORD=2|OwnerIndex=882|OwnerPartId=1|FormalType=1|PinConglomerate=24|PinLength=30|Location.X=1250|Location.Y=338|Name=34|Designator=34|PinPropagationDelay=0.000000E+000
|RECORD=2|OwnerIndex=882|OwnerPartId=1|FormalType=1|PinConglomerate=26|PinLength=30|Location.X=1190|Location.Y=328|Name=35|Designator=35|PinPropagationDelay=0.000000E+000
|RECORD=2|OwnerIndex=882|OwnerPartId=1|FormalType=1|PinConglomerate=24|PinLength=30|Location.X=1250|Location.Y=328|Name=36|Designator=36|PinPropagationDelay=0.000000E+000
|RECORD=2|OwnerIndex=882|OwnerPartId=1|FormalType=1|PinConglomerate=26|PinLength=30|Location.X=1190|Location.Y=318|Name=37|Designator=37|PinPropagationDelay=0.000000E+000
|RECORD=2|OwnerIndex=882|OwnerPartId=1|FormalType=1|PinConglomerate=24|PinLength=30|Location.X=1250|Location.Y=318|Name=38|Designator=38|PinPropagationDelay=0.000000E+000
|RECORD=2|OwnerIndex=882|OwnerPartId=1|FormalType=1|PinConglomerate=26|PinLength=30|Location.X=1190|Location.Y=308|Name=39|Designator=39|PinPropagationDelay=0.000000E+000
|RECORD=2|OwnerIndex=882|OwnerPartId=1|FormalType=1|PinConglomerate=24|PinLength=30|Location.X=1250|Location.Y=308|Name=40|Designator=40|PinPropagationDelay=0.000000E+000
|RECORD=2|OwnerIndex=882|OwnerPartId=1|FormalType=1|PinConglomerate=26|PinLength=30|Location.X=1190|Location.Y=298|Name=41|Designator=41|PinPropagationDelay=0.000000E+000
|RECORD=2|OwnerIndex=882|OwnerPartId=1|FormalType=1|PinConglomerate=24|PinLength=30|Location.X=1250|Location.Y=298|Name=42|Designator=42|PinPropagationDelay=0.000000E+000
|RECORD=2|OwnerIndex=882|OwnerPartId=1|FormalType=1|PinConglomerate=26|PinLength=30|Location.X=1190|Location.Y=288|Name=43|Designator=43|PinPropagationDelay=0.000000E+000
|RECORD=2|OwnerIndex=882|OwnerPartId=1|FormalType=1|PinConglomerate=24|PinLength=30|Location.X=1250|Location.Y=288|Name=44|Designator=44|PinPropagationDelay=0.000000E+000
|RECORD=2|OwnerIndex=882|OwnerPartId=1|FormalType=1|PinConglomerate=26|PinLength=30|Location.X=1190|Location.Y=278|Name=45|Designator=45|PinPropagationDelay=0.000000E+000
|RECORD=2|OwnerIndex=882|OwnerPartId=1|FormalType=1|PinConglomerate=24|PinLength=30|Location.X=1250|Location.Y=278|Name=46|Designator=46|PinPropagationDelay=0.000000E+000
|RECORD=2|OwnerIndex=882|OwnerPartId=1|FormalType=1|PinConglomerate=26|PinLength=30|Location.X=1190|Location.Y=268|Name=47|Designator=47|PinPropagationDelay=0.000000E+000
|RECORD=2|OwnerIndex=882|OwnerPartId=1|FormalType=1|PinConglomerate=24|PinLength=30|Location.X=1250|Location.Y=268|Name=48|Designator=48|PinPropagationDelay=0.000000E+000
|RECORD=2|OwnerIndex=882|OwnerPartId=1|FormalType=1|PinConglomerate=26|PinLength=30|Location.X=1190|Location.Y=258|Name=49|Designator=49|PinPropagationDelay=0.000000E+000
|RECORD=2|OwnerIndex=882|OwnerPartId=1|FormalType=1|PinConglomerate=24|PinLength=30|Location.X=1250|Location.Y=258|Name=50|Designator=50|PinPropagationDelay=0.000000E+000
|RECORD=2|OwnerIndex=882|OwnerPartId=1|FormalType=1|PinConglomerate=26|PinLength=30|Location.X=1190|Location.Y=248|Name=51|Designator=51|PinPropagationDelay=0.000000E+000
|RECORD=2|OwnerIndex=882|OwnerPartId=1|FormalType=1|PinConglomerate=24|PinLength=30|Location.X=1250|Location.Y=248|Name=52|Designator=52|PinPropagationDelay=0.000000E+000
|RECORD=2|OwnerIndex=882|OwnerPartId=1|FormalType=1|PinConglomerate=26|PinLength=30|Location.X=1190|Location.Y=238|Name=53|Designator=53|PinPropagationDelay=0.000000E+000
|RECORD=2|OwnerIndex=882|OwnerPartId=1|FormalType=1|PinConglomerate=24|PinLength=30|Location.X=1250|Location.Y=238|Name=54|Designator=54|PinPropagationDelay=0.000000E+000
|RECORD=2|OwnerIndex=882|OwnerPartId=1|FormalType=1|PinConglomerate=26|PinLength=30|Location.X=1190|Location.Y=228|Name=55|Designator=55|PinPropagationDelay=0.000000E+000
|RECORD=2|OwnerIndex=882|OwnerPartId=1|FormalType=1|PinConglomerate=24|PinLength=30|Location.X=1250|Location.Y=228|Name=56|Designator=56|PinPropagationDelay=0.000000E+000
|RECORD=2|OwnerIndex=882|OwnerPartId=1|FormalType=1|PinConglomerate=26|PinLength=30|Location.X=1190|Location.Y=218|Name=57|Designator=57|PinPropagationDelay=0.000000E+000
|RECORD=2|OwnerIndex=882|OwnerPartId=1|FormalType=1|PinConglomerate=24|PinLength=30|Location.X=1250|Location.Y=218|Name=58|Designator=58|PinPropagationDelay=0.000000E+000
|RECORD=2|OwnerIndex=882|OwnerPartId=1|FormalType=1|PinConglomerate=26|PinLength=30|Location.X=1190|Location.Y=208|Name=59|Designator=59|PinPropagationDelay=0.000000E+000
|RECORD=2|OwnerIndex=882|OwnerPartId=1|FormalType=1|PinConglomerate=24|PinLength=30|Location.X=1250|Location.Y=208|Name=60|Designator=60|PinPropagationDelay=0.000000E+000
|RECORD=2|OwnerIndex=882|OwnerPartId=1|FormalType=1|PinConglomerate=26|PinLength=30|Location.X=1190|Location.Y=198|Name=61|Designator=61|PinPropagationDelay=0.000000E+000
|RECORD=2|OwnerIndex=882|OwnerPartId=1|FormalType=1|PinConglomerate=24|PinLength=30|Location.X=1250|Location.Y=198|Name=62|Designator=62|PinPropagationDelay=0.000000E+000
|RECORD=2|OwnerIndex=882|OwnerPartId=1|FormalType=1|PinConglomerate=26|PinLength=30|Location.X=1190|Location.Y=188|Name=63|Designator=63|PinPropagationDelay=0.000000E+000
|RECORD=2|OwnerIndex=882|OwnerPartId=1|FormalType=1|PinConglomerate=24|PinLength=30|Location.X=1250|Location.Y=188|Name=64|Designator=64|PinPropagationDelay=0.000000E+000
|RECORD=2|OwnerIndex=882|OwnerPartId=1|FormalType=1|PinConglomerate=26|PinLength=30|Location.X=1190|Location.Y=178|Name=65|Designator=65|PinPropagationDelay=0.000000E+000
|RECORD=2|OwnerIndex=882|OwnerPartId=1|FormalType=1|PinConglomerate=24|PinLength=30|Location.X=1250|Location.Y=178|Name=66|Designator=66|PinPropagationDelay=0.000000E+000
|RECORD=2|OwnerIndex=882|OwnerPartId=1|FormalType=1|PinConglomerate=26|PinLength=30|Location.X=1190|Location.Y=168|Name=67|Designator=67|PinPropagationDelay=0.000000E+000
|RECORD=2|OwnerIndex=882|OwnerPartId=1|FormalType=1|PinConglomerate=24|PinLength=30|Location.X=1250|Location.Y=168|Name=68|Designator=68|PinPropagationDelay=0.000000E+000
|RECORD=2|OwnerIndex=882|OwnerPartId=1|FormalType=1|PinConglomerate=26|PinLength=30|Location.X=1190|Location.Y=158|Name=69|Designator=69|PinPropagationDelay=0.000000E+000
|RECORD=2|OwnerIndex=882|OwnerPartId=1|FormalType=1|PinConglomerate=24|PinLength=30|Location.X=1250|Location.Y=158|Name=70|Designator=70|PinPropagationDelay=0.000000E+000
|RECORD=2|OwnerIndex=882|OwnerPartId=1|FormalType=1|PinConglomerate=26|PinLength=30|Location.X=1190|Location.Y=148|Name=71|Designator=71|PinPropagationDelay=0.000000E+000
|RECORD=2|OwnerIndex=882|OwnerPartId=1|FormalType=1|PinConglomerate=24|PinLength=30|Location.X=1250|Location.Y=148|Name=72|Designator=72|PinPropagationDelay=0.000000E+000
|RECORD=2|OwnerIndex=882|OwnerPartId=1|FormalType=1|PinConglomerate=26|PinLength=30|Location.X=1190|Location.Y=138|Name=73|Designator=73|PinPropagationDelay=0.000000E+000
|RECORD=2|OwnerIndex=882|OwnerPartId=1|FormalType=1|PinConglomerate=24|PinLength=30|Location.X=1250|Location.Y=138|Name=74|Designator=74|PinPropagationDelay=0.000000E+000
|RECORD=2|OwnerIndex=882|OwnerPartId=1|FormalType=1|PinConglomerate=26|PinLength=30|Location.X=1190|Location.Y=128|Name=75|Designator=75|PinPropagationDelay=0.000000E+000
|RECORD=2|OwnerIndex=882|OwnerPartId=1|FormalType=1|PinConglomerate=24|PinLength=30|Location.X=1250|Location.Y=128|Name=76|Designator=76|PinPropagationDelay=0.000000E+000
|RECORD=2|OwnerIndex=882|OwnerPartId=1|FormalType=1|PinConglomerate=26|PinLength=30|Location.X=1190|Location.Y=118|Name=77|Designator=77|PinPropagationDelay=0.000000E+000
|RECORD=2|OwnerIndex=882|OwnerPartId=1|FormalType=1|PinConglomerate=24|PinLength=30|Location.X=1250|Location.Y=118|Name=78|Designator=78|PinPropagationDelay=0.000000E+000
|RECORD=2|OwnerIndex=882|OwnerPartId=1|FormalType=1|PinConglomerate=26|PinLength=30|Location.X=1190|Location.Y=108|Name=79|Designator=79|PinPropagationDelay=0.000000E+000
|RECORD=2|OwnerIndex=882|OwnerPartId=1|FormalType=1|PinConglomerate=24|PinLength=30|Location.X=1250|Location.Y=108|Name=80|Designator=80|PinPropagationDelay=0.000000E+000
|RECORD=2|OwnerIndex=882|OwnerPartId=1|FormalType=1|PinConglomerate=26|PinLength=30|Location.X=1190|Location.Y=98|Name=81|Designator=81|PinPropagationDelay=0.000000E+000
|RECORD=2|OwnerIndex=882|OwnerPartId=1|FormalType=1|PinConglomerate=24|PinLength=30|Location.X=1250|Location.Y=98|Name=82|Designator=82|PinPropagationDelay=0.000000E+000
|RECORD=2|OwnerIndex=882|OwnerPartId=1|FormalType=1|PinConglomerate=26|PinLength=30|Location.X=1190|Location.Y=88|Name=83|Designator=83|PinPropagationDelay=0.000000E+000
|RECORD=2|OwnerIndex=882|OwnerPartId=1|FormalType=1|PinConglomerate=24|PinLength=30|Location.X=1250|Location.Y=88|Name=84|Designator=84|PinPropagationDelay=0.000000E+000
|RECORD=34|OwnerIndex=882|IndexInSheet=-1|OwnerPartId=-1|Location.X=1190|Location.Y=508|Color=8388608|FontID=1|Text=J37|Name=Designator|ReadOnlyState=1
|RECORD=41|OwnerIndex=882|IndexInSheet=-1|OwnerPartId=-1|Location.X=1190|Location.Y=68|Color=8388608|FontID=1|Text=Single FPGA Conn|Name=Comment
|RECORD=44|OwnerIndex=882
|RECORD=45|OwnerIndex=1057|IndexInSheet=-1|ModelName=SingleFPGAConn|ModelType=PCBLIB|DatafileCount=1|ModelDatafileEntity0=SingleFPGAConn|ModelDatafileKind0=PCBLib|IsCurrent=T
|RECORD=46|OwnerIndex=1058
|RECORD=48|OwnerIndex=1058
|RECORD=17|IndexInSheet=315|OwnerPartId=-1|ShowNetName=T|Location.X=1125|Location.Y=990|Orientation=2|Color=255|FontID=1|Text=GPS1_PIN15|IsCrossSheetConnector=T
|RECORD=17|IndexInSheet=316|OwnerPartId=-1|ShowNetName=T|Location.X=1125|Location.Y=980|Orientation=2|Color=255|FontID=1|Text=GPS1_PIN14|IsCrossSheetConnector=T
|RECORD=17|IndexInSheet=317|OwnerPartId=-1|ShowNetName=T|Location.X=1125|Location.Y=970|Orientation=2|Color=255|FontID=1|Text=GPS1_PIN12|IsCrossSheetConnector=T
|RECORD=17|IndexInSheet=318|OwnerPartId=-1|ShowNetName=T|Location.X=1345|Location.Y=990|Color=255|FontID=1|Text=GPS1_PIN13|IsCrossSheetConnector=T
|RECORD=17|IndexInSheet=319|OwnerPartId=-1|ShowNetName=T|Location.X=1345|Location.Y=980|Color=255|FontID=1|Text=GPS1_PIN11|IsCrossSheetConnector=T
|RECORD=17|IndexInSheet=320|OwnerPartId=-1|ShowNetName=T|Location.X=995|Location.Y=670|Orientation=2|Color=255|FontID=1|Text=GPS2_PIN15|IsCrossSheetConnector=T
|RECORD=17|IndexInSheet=321|OwnerPartId=-1|ShowNetName=T|Location.X=990|Location.Y=630|Orientation=2|Color=255|FontID=1|Text=GPS2_PIN13|IsCrossSheetConnector=T
|RECORD=17|IndexInSheet=322|OwnerPartId=-1|ShowNetName=T|Location.X=990|Location.Y=620|Orientation=2|Color=255|FontID=1|Text=GPS2_PIN11|IsCrossSheetConnector=T
|RECORD=17|IndexInSheet=323|OwnerPartId=-1|ShowNetName=T|Location.X=1415|Location.Y=615|Color=255|FontID=1|Text=GPS2_PIN12|IsCrossSheetConnector=T
|RECORD=17|IndexInSheet=324|OwnerPartId=-1|ShowNetName=T|Location.X=1415|Location.Y=605|Color=255|FontID=1|Text=GPS2_PIN14|IsCrossSheetConnector=T
|RECORD=17|IndexInSheet=325|OwnerPartId=-1|ShowNetName=T|Location.X=995|Location.Y=680|Orientation=2|Color=255|FontID=1|Text=BNO_INT|IsCrossSheetConnector=T
|RECORD=27|IndexInSheet=326|OwnerPartId=-1|LineWidth=1|Color=8388608|LocationCount=2|X1=320|Y1=108|X2=460|Y2=108
|RECORD=27|IndexInSheet=327|OwnerPartId=-1|LineWidth=1|Color=8388608|LocationCount=2|X1=320|Y1=118|X2=460|Y2=118
|RECORD=27|IndexInSheet=328|OwnerPartId=-1|LineWidth=1|Color=8388608|LocationCount=2|X1=320|Y1=388|X2=460|Y2=388
|RECORD=27|IndexInSheet=329|OwnerPartId=-1|LineWidth=1|Color=8388608|LocationCount=2|X1=320|Y1=398|X2=460|Y2=398
|RECORD=27|IndexInSheet=330|OwnerPartId=-1|LineWidth=1|Color=8388608|LocationCount=2|X1=460|Y1=608|X2=330|Y2=608
|RECORD=27|IndexInSheet=331|OwnerPartId=-1|LineWidth=1|Color=8388608|LocationCount=2|X1=460|Y1=618|X2=330|Y2=618
|RECORD=27|IndexInSheet=332|OwnerPartId=-1|LineWidth=1|Color=8388608|LocationCount=2|X1=460|Y1=628|X2=330|Y2=628
|RECORD=27|IndexInSheet=333|OwnerPartId=-1|LineWidth=1|Color=8388608|LocationCount=2|X1=460|Y1=638|X2=330|Y2=638
|RECORD=27|IndexInSheet=334|OwnerPartId=-1|LineWidth=1|Color=8388608|LocationCount=2|X1=460|Y1=658|X2=330|Y2=658
|RECORD=27|IndexInSheet=335|OwnerPartId=-1|LineWidth=1|Color=8388608|LocationCount=2|X1=460|Y1=158|X2=400|Y2=158
|RECORD=27|IndexInSheet=336|OwnerPartId=-1|LineWidth=1|Color=8388608|LocationCount=2|X1=460|Y1=208|X2=400|Y2=208
|RECORD=27|IndexInSheet=337|OwnerPartId=-1|LineWidth=1|Color=8388608|LocationCount=2|X1=460|Y1=258|X2=400|Y2=258
|RECORD=27|IndexInSheet=338|OwnerPartId=-1|LineWidth=1|Color=8388608|LocationCount=2|X1=460|Y1=308|X2=400|Y2=308
|RECORD=27|IndexInSheet=339|OwnerPartId=-1|LineWidth=1|Color=8388608|LocationCount=2|X1=460|Y1=358|X2=400|Y2=358
|RECORD=27|IndexInSheet=340|OwnerPartId=-1|LineWidth=1|Color=8388608|LocationCount=2|X1=460|Y1=408|X2=400|Y2=408
|RECORD=27|IndexInSheet=341|OwnerPartId=-1|LineWidth=1|Color=8388608|LocationCount=9|X1=460|Y1=458|X2=400|Y2=458|X3=400|Y3=408|X4=400|Y4=358|X5=400|Y5=308|X6=400|Y6=258|X7=400|Y7=208|X8=400|Y8=158|X9=400|Y9=68
|RECORD=27|IndexInSheet=342|OwnerPartId=-1|LineWidth=1|Color=8388608|LocationCount=2|X1=460|Y1=648|X2=410|Y2=648
|RECORD=27|IndexInSheet=343|OwnerPartId=-1|LineWidth=1|Color=8388608|LocationCount=2|X1=460|Y1=698|X2=410|Y2=698
|RECORD=27|IndexInSheet=344|OwnerPartId=-1|LineWidth=1|Color=8388608|LocationCount=2|X1=460|Y1=748|X2=410|Y2=748
|RECORD=27|IndexInSheet=345|OwnerPartId=-1|LineWidth=1|Color=8388608|LocationCount=2|X1=460|Y1=798|X2=410|Y2=798
|RECORD=27|IndexInSheet=346|OwnerPartId=-1|LineWidth=1|Color=8388608|LocationCount=2|X1=460|Y1=848|X2=410|Y2=848
|RECORD=27|IndexInSheet=347|OwnerPartId=-1|LineWidth=1|Color=8388608|LocationCount=2|X1=460|Y1=898|X2=410|Y2=898
|RECORD=27|IndexInSheet=348|OwnerPartId=-1|LineWidth=1|Color=8388608|LocationCount=9|X1=460|Y1=948|X2=410|Y2=948|X3=410|Y3=898|X4=410|Y4=848|X5=410|Y5=798|X6=410|Y6=748|X7=410|Y7=698|X8=410|Y8=648|X9=410|Y9=568
|RECORD=27|IndexInSheet=349|OwnerPartId=-1|LineWidth=1|Color=8388608|LocationCount=6|X1=460|Y1=958|X2=410|Y2=958|X3=410|Y3=968|X4=410|Y4=978|X5=410|Y5=988|X6=410|Y6=1008
|RECORD=27|IndexInSheet=350|OwnerPartId=-1|LineWidth=1|Color=8388608|LocationCount=2|X1=460|Y1=968|X2=410|Y2=968
|RECORD=27|IndexInSheet=351|OwnerPartId=-1|LineWidth=1|Color=8388608|LocationCount=2|X1=460|Y1=978|X2=410|Y2=978
|RECORD=27|IndexInSheet=352|OwnerPartId=-1|LineWidth=1|Color=8388608|LocationCount=2|X1=460|Y1=988|X2=410|Y2=988
|RECORD=27|IndexInSheet=353|OwnerPartId=-1|LineWidth=1|Color=8388608|LocationCount=2|X1=580|Y1=108|X2=690|Y2=108
|RECORD=27|IndexInSheet=354|OwnerPartId=-1|LineWidth=1|Color=8388608|LocationCount=2|X1=580|Y1=118|X2=690|Y2=118
|RECORD=27|IndexInSheet=355|OwnerPartId=-1|LineWidth=1|Color=8388608|LocationCount=2|X1=580|Y1=158|X2=620|Y2=158
|RECORD=27|IndexInSheet=356|OwnerPartId=-1|LineWidth=1|Color=8388608|LocationCount=2|X1=580|Y1=208|X2=620|Y2=208
|RECORD=27|IndexInSheet=357|OwnerPartId=-1|LineWidth=1|Color=8388608|LocationCount=2|X1=580|Y1=258|X2=620|Y2=258
|RECORD=27|IndexInSheet=358|OwnerPartId=-1|LineWidth=1|Color=8388608|LocationCount=2|X1=580|Y1=308|X2=620|Y2=308
|RECORD=27|IndexInSheet=359|OwnerPartId=-1|LineWidth=1|Color=8388608|LocationCount=2|X1=580|Y1=358|X2=620|Y2=358
|RECORD=27|IndexInSheet=360|OwnerPartId=-1|LineWidth=1|Color=8388608|LocationCount=2|X1=580|Y1=408|X2=620|Y2=408
|RECORD=27|IndexInSheet=361|OwnerPartId=-1|LineWidth=1|Color=8388608|LocationCount=2|X1=580|Y1=648|X2=600|Y2=648
|RECORD=27|IndexInSheet=362|OwnerPartId=-1|LineWidth=1|Color=8388608|LocationCount=2|X1=580|Y1=698|X2=600|Y2=698
|RECORD=27|IndexInSheet=363|OwnerPartId=-1|LineWidth=1|Color=8388608|LocationCount=2|X1=580|Y1=748|X2=600|Y2=748
|RECORD=27|IndexInSheet=364|OwnerPartId=-1|LineWidth=1|Color=8388608|LocationCount=2|X1=580|Y1=798|X2=600|Y2=798
|RECORD=27|IndexInSheet=365|OwnerPartId=-1|LineWidth=1|Color=8388608|LocationCount=2|X1=640|Y1=828|X2=580|Y2=828
|RECORD=27|IndexInSheet=366|OwnerPartId=-1|LineWidth=1|Color=8388608|LocationCount=2|X1=640|Y1=838|X2=580|Y2=838
|RECORD=27|IndexInSheet=367|OwnerPartId=-1|LineWidth=1|Color=8388608|LocationCount=2|X1=580|Y1=848|X2=600|Y2=848
|RECORD=27|IndexInSheet=368|OwnerPartId=-1|LineWidth=1|Color=8388608|LocationCount=2|X1=640|Y1=888|X2=580|Y2=888
|RECORD=27|IndexInSheet=369|OwnerPartId=-1|LineWidth=1|Color=8388608|LocationCount=2|X1=580|Y1=898|X2=600|Y2=898
|RECORD=27|IndexInSheet=370|OwnerPartId=-1|LineWidth=1|Color=8388608|LocationCount=2|X1=580|Y1=968|X2=600|Y2=968
|RECORD=27|IndexInSheet=371|OwnerPartId=-1|LineWidth=1|Color=8388608|LocationCount=2|X1=580|Y1=978|X2=600|Y2=978
|RECORD=27|IndexInSheet=372|OwnerPartId=-1|LineWidth=1|Color=8388608|LocationCount=2|X1=580|Y1=988|X2=600|Y2=988
|RECORD=27|IndexInSheet=373|OwnerPartId=-1|LineWidth=1|Color=8388608|LocationCount=2|X1=1160|Y1=318|X2=1060|Y2=318
|RECORD=27|IndexInSheet=374|OwnerPartId=-1|LineWidth=1|Color=8388608|LocationCount=2|X1=1160|Y1=328|X2=1060|Y2=328
|RECORD=27|IndexInSheet=375|OwnerPartId=-1|LineWidth=1|Color=8388608|LocationCount=2|X1=1160|Y1=348|X2=1060|Y2=348
|RECORD=27|IndexInSheet=376|OwnerPartId=-1|LineWidth=1|Color=8388608|LocationCount=2|X1=1160|Y1=358|X2=1060|Y2=358
|RECORD=27|IndexInSheet=377|OwnerPartId=-1|LineWidth=1|Color=8388608|LocationCount=2|X1=1160|Y1=378|X2=1060|Y2=378
|RECORD=27|IndexInSheet=378|OwnerPartId=-1|LineWidth=1|Color=8388608|LocationCount=2|X1=1160|Y1=388|X2=1060|Y2=388
|RECORD=27|IndexInSheet=379|OwnerPartId=-1|LineWidth=1|Color=8388608|LocationCount=2|X1=1160|Y1=408|X2=1060|Y2=408
|RECORD=27|IndexInSheet=380|OwnerPartId=-1|LineWidth=1|Color=8388608|LocationCount=2|X1=1160|Y1=418|X2=1060|Y2=418
|RECORD=27|IndexInSheet=381|OwnerPartId=-1|LineWidth=1|Color=8388608|LocationCount=2|X1=1170|Y1=598|X2=1060|Y2=598
|RECORD=27|IndexInSheet=382|OwnerPartId=-1|LineWidth=1|Color=8388608|LocationCount=2|X1=1060|Y1=658|X2=1170|Y2=658
|RECORD=27|IndexInSheet=383|OwnerPartId=-1|LineWidth=1|Color=8388608|LocationCount=2|X1=1060|Y1=688|X2=1170|Y2=688
|RECORD=27|IndexInSheet=384|OwnerPartId=-1|LineWidth=1|Color=8388608|LocationCount=2|X1=1060|Y1=758|X2=1170|Y2=758
|RECORD=27|IndexInSheet=385|OwnerPartId=-1|LineWidth=1|Color=8388608|LocationCount=2|X1=1060|Y1=778|X2=1170|Y2=778
|RECORD=27|IndexInSheet=386|OwnerPartId=-1|LineWidth=1|Color=8388608|LocationCount=2|X1=1170|Y1=808|X2=1060|Y2=808
|RECORD=27|IndexInSheet=387|OwnerPartId=-1|LineWidth=1|Color=8388608|LocationCount=2|X1=1170|Y1=818|X2=1060|Y2=818
|RECORD=27|IndexInSheet=388|OwnerPartId=-1|LineWidth=1|Color=8388608|LocationCount=2|X1=1059|Y1=858|X2=1170|Y2=858
|RECORD=27|IndexInSheet=389|OwnerPartId=-1|LineWidth=1|Color=8388608|LocationCount=2|X1=1059|Y1=868|X2=1170|Y2=868
|RECORD=27|IndexInSheet=390|OwnerPartId=-1|LineWidth=1|Color=8388608|LocationCount=2|X1=1059|Y1=878|X2=1170|Y2=878
|RECORD=27|IndexInSheet=391|OwnerPartId=-1|LineWidth=1|Color=8388608|LocationCount=2|X1=1059|Y1=888|X2=1170|Y2=888
|RECORD=27|IndexInSheet=392|OwnerPartId=-1|LineWidth=1|Color=8388608|LocationCount=3|X1=1060|Y1=938|X2=1160|Y2=938|X3=1170|Y3=938
|RECORD=27|IndexInSheet=393|OwnerPartId=-1|LineWidth=1|Color=8388608|LocationCount=2|X1=1160|Y1=158|X2=1110|Y2=158
|RECORD=27|IndexInSheet=394|OwnerPartId=-1|LineWidth=1|Color=8388608|LocationCount=2|X1=1160|Y1=208|X2=1110|Y2=208
|RECORD=27|IndexInSheet=395|OwnerPartId=-1|LineWidth=1|Color=8388608|LocationCount=2|X1=1160|Y1=258|X2=1110|Y2=258
|RECORD=27|IndexInSheet=396|OwnerPartId=-1|LineWidth=1|Color=8388608|LocationCount=2|X1=1160|Y1=308|X2=1110|Y2=308
|RECORD=27|IndexInSheet=397|OwnerPartId=-1|LineWidth=1|Color=8388608|LocationCount=2|X1=1160|Y1=338|X2=1110|Y2=338
|RECORD=27|IndexInSheet=398|OwnerPartId=-1|LineWidth=1|Color=8388608|LocationCount=2|X1=1160|Y1=368|X2=1110|Y2=368
|RECORD=27|IndexInSheet=399|OwnerPartId=-1|LineWidth=1|Color=8388608|LocationCount=2|X1=1160|Y1=398|X2=1110|Y2=398
|RECORD=27|IndexInSheet=400|OwnerPartId=-1|LineWidth=1|Color=8388608|LocationCount=2|X1=1160|Y1=428|X2=1110|Y2=428
|RECORD=27|IndexInSheet=401|OwnerPartId=-1|LineWidth=1|Color=8388608|LocationCount=11|X1=1160|Y1=458|X2=1110|Y2=458|X3=1110|Y3=428|X4=1110|Y4=398|X5=1110|Y5=368|X6=1110|Y6=338|X7=1110|Y7=308|X8=1110|Y8=258|X9=1110|Y9=208|X10=1110|Y10=158|X11=1110|Y11=78
|RECORD=27|IndexInSheet=402|OwnerPartId=-1|LineWidth=1|Color=8388608|LocationCount=2|X1=1170|Y1=648|X2=1130|Y2=648
|RECORD=27|IndexInSheet=403|OwnerPartId=-1|LineWidth=1|Color=8388608|LocationCount=2|X1=1170|Y1=698|X2=1130|Y2=698
|RECORD=27|IndexInSheet=404|OwnerPartId=-1|LineWidth=1|Color=8388608|LocationCount=2|X1=1170|Y1=748|X2=1130|Y2=748
|RECORD=27|IndexInSheet=405|OwnerPartId=-1|LineWidth=1|Color=8388608|LocationCount=2|X1=1170|Y1=798|X2=1130|Y2=798
|RECORD=27|IndexInSheet=406|OwnerPartId=-1|LineWidth=1|Color=8388608|LocationCount=2|X1=1170|Y1=848|X2=1130|Y2=848
|RECORD=27|IndexInSheet=407|OwnerPartId=-1|LineWidth=1|Color=8388608|LocationCount=2|X1=1170|Y1=898|X2=1130|Y2=898
|RECORD=27|IndexInSheet=408|OwnerPartId=-1|LineWidth=1|Color=8388608|LocationCount=9|X1=1170|Y1=948|X2=1130|Y2=948|X3=1130|Y3=898|X4=1130|Y4=848|X5=1130|Y5=798|X6=1130|Y6=748|X7=1130|Y7=698|X8=1130|Y8=648|X9=1130|Y9=568
|RECORD=27|IndexInSheet=409|OwnerPartId=-1|LineWidth=1|Color=8388608|LocationCount=3|X1=1170|Y1=928|X2=1160|Y2=928|X3=1160|Y3=938
|RECORD=27|IndexInSheet=410|OwnerPartId=-1|LineWidth=1|Color=8388608|LocationCount=2|X1=1280|Y1=158|X2=1310|Y2=158
|RECORD=27|IndexInSheet=411|OwnerPartId=-1|LineWidth=1|Color=8388608|LocationCount=2|X1=1280|Y1=208|X2=1310|Y2=208
|RECORD=27|IndexInSheet=412|OwnerPartId=-1|LineWidth=1|Color=8388608|LocationCount=2|X1=1280|Y1=258|X2=1310|Y2=258
|RECORD=27|IndexInSheet=413|OwnerPartId=-1|LineWidth=1|Color=8388608|LocationCount=2|X1=1280|Y1=308|X2=1310|Y2=308
|RECORD=27|IndexInSheet=414|OwnerPartId=-1|LineWidth=1|Color=8388608|LocationCount=2|X1=1280|Y1=318|X2=1360|Y2=318
|RECORD=27|IndexInSheet=415|OwnerPartId=-1|LineWidth=1|Color=8388608|LocationCount=2|X1=1280|Y1=328|X2=1360|Y2=328
|RECORD=27|IndexInSheet=416|OwnerPartId=-1|LineWidth=1|Color=8388608|LocationCount=2|X1=1280|Y1=348|X2=1360|Y2=348
|RECORD=27|IndexInSheet=417|OwnerPartId=-1|LineWidth=1|Color=8388608|LocationCount=2|X1=1280|Y1=358|X2=1360|Y2=358
|RECORD=27|IndexInSheet=418|OwnerPartId=-1|LineWidth=1|Color=8388608|LocationCount=2|X1=1280|Y1=378|X2=1360|Y2=378
|RECORD=27|IndexInSheet=419|OwnerPartId=-1|LineWidth=1|Color=8388608|LocationCount=2|X1=1280|Y1=388|X2=1360|Y2=388
|RECORD=27|IndexInSheet=420|OwnerPartId=-1|LineWidth=1|Color=8388608|LocationCount=2|X1=1280|Y1=408|X2=1360|Y2=408
|RECORD=27|IndexInSheet=421|OwnerPartId=-1|LineWidth=1|Color=8388608|LocationCount=2|X1=1280|Y1=418|X2=1360|Y2=418
|RECORD=27|IndexInSheet=422|OwnerPartId=-1|LineWidth=1|Color=8388608|LocationCount=2|X1=1280|Y1=438|X2=1360|Y2=438
|RECORD=27|IndexInSheet=423|OwnerPartId=-1|LineWidth=1|Color=8388608|LocationCount=2|X1=1280|Y1=448|X2=1360|Y2=448
|RECORD=27|IndexInSheet=424|OwnerPartId=-1|LineWidth=1|Color=8388608|LocationCount=2|X1=1290|Y1=648|X2=1320|Y2=648
|RECORD=27|IndexInSheet=425|OwnerPartId=-1|LineWidth=1|Color=8388608|LocationCount=2|X1=1290|Y1=698|X2=1320|Y2=698
|RECORD=27|IndexInSheet=426|OwnerPartId=-1|LineWidth=1|Color=8388608|LocationCount=2|X1=1290|Y1=748|X2=1320|Y2=748
|RECORD=27|IndexInSheet=427|OwnerPartId=-1|LineWidth=1|Color=8388608|LocationCount=2|X1=1290|Y1=798|X2=1320|Y2=798
|RECORD=27|IndexInSheet=428|OwnerPartId=-1|LineWidth=1|Color=8388608|LocationCount=2|X1=1290|Y1=848|X2=1320|Y2=848
|RECORD=27|IndexInSheet=429|OwnerPartId=-1|LineWidth=1|Color=8388608|LocationCount=2|X1=1290|Y1=898|X2=1320|Y2=898
|RECORD=27|IndexInSheet=430|OwnerPartId=-1|LineWidth=1|Color=8388608|LocationCount=2|X1=1350|Y1=958|X2=1290|Y2=958
|RECORD=27|IndexInSheet=431|OwnerPartId=-1|LineWidth=1|Color=8388608|LocationCount=9|X1=580|Y1=948|X2=600|Y2=948|X3=600|Y3=898|X4=600|Y4=848|X5=600|Y5=798|X6=600|Y6=748|X7=600|Y7=698|X8=600|Y8=648|X9=600|Y9=568
|RECORD=27|IndexInSheet=432|OwnerPartId=-1|LineWidth=1|Color=8388608|LocationCount=6|X1=580|Y1=958|X2=600|Y2=958|X3=600|Y3=968|X4=600|Y4=978|X5=600|Y5=988|X6=600|Y6=1008
|RECORD=27|IndexInSheet=433|OwnerPartId=-1|LineWidth=1|Color=8388608|LocationCount=2|X1=1290|Y1=598|X2=1350|Y2=598
|RECORD=27|IndexInSheet=434|OwnerPartId=-1|LineWidth=1|Color=8388608|LocationCount=2|X1=1350|Y1=628|X2=1290|Y2=628
|RECORD=27|IndexInSheet=435|OwnerPartId=-1|LineWidth=1|Color=8388608|LocationCount=2|X1=1350|Y1=638|X2=1290|Y2=638
|RECORD=27|IndexInSheet=436|OwnerPartId=-1|LineWidth=1|Color=8388608|LocationCount=2|X1=1350|Y1=858|X2=1290|Y2=858
|RECORD=27|IndexInSheet=437|OwnerPartId=-1|LineWidth=1|Color=8388608|LocationCount=2|X1=1350|Y1=868|X2=1290|Y2=868
|RECORD=27|IndexInSheet=438|OwnerPartId=-1|LineWidth=1|Color=8388608|LocationCount=9|X1=580|Y1=458|X2=620|Y2=458|X3=620|Y3=408|X4=620|Y4=358|X5=620|Y5=308|X6=620|Y6=258|X7=620|Y7=208|X8=620|Y8=158|X9=620|Y9=68
|RECORD=27|IndexInSheet=439|OwnerPartId=-1|LineWidth=1|Color=8388608|LocationCount=7|X1=1280|Y1=458|X2=1310|Y2=458|X3=1310|Y3=308|X4=1310|Y4=258|X5=1310|Y5=208|X6=1310|Y6=158|X7=1310|Y7=78
|RECORD=27|IndexInSheet=440|OwnerPartId=-1|LineWidth=1|Color=8388608|LocationCount=2|X1=1170|Y1=728|X2=1060|Y2=728
|RECORD=27|IndexInSheet=441|OwnerPartId=-1|LineWidth=1|Color=8388608|LocationCount=2|X1=460|Y1=498|X2=318|Y2=498
|RECORD=27|IndexInSheet=442|OwnerPartId=-1|LineWidth=1|Color=8388608|LocationCount=2|X1=580|Y1=498|X2=690|Y2=498
|RECORD=27|IndexInSheet=443|OwnerPartId=-1|LineWidth=1|Color=8388608|LocationCount=2|X1=1170|Y1=608|X2=1060|Y2=608
|RECORD=27|IndexInSheet=444|OwnerPartId=-1|LineWidth=1|Color=8388608|LocationCount=2|X1=1170|Y1=638|X2=1061|Y2=638
|RECORD=27|IndexInSheet=445|OwnerPartId=-1|LineWidth=1|Color=8388608|LocationCount=2|X1=460|Y1=478|X2=319|Y2=478
|RECORD=27|IndexInSheet=446|OwnerPartId=-1|LineWidth=1|Color=8388608|LocationCount=2|X1=460|Y1=448|X2=319|Y2=448
|RECORD=27|IndexInSheet=447|OwnerPartId=-1|LineWidth=1|Color=8388608|LocationCount=2|X1=460|Y1=468|X2=319|Y2=468
|RECORD=27|IndexInSheet=448|OwnerPartId=-1|LineWidth=1|Color=8388608|LocationCount=2|X1=580|Y1=448|X2=690|Y2=448
|RECORD=27|IndexInSheet=449|OwnerPartId=-1|LineWidth=1|Color=8388608|LocationCount=2|X1=580|Y1=438|X2=690|Y2=438
|RECORD=27|IndexInSheet=450|OwnerPartId=-1|LineWidth=1|Color=8388608|LocationCount=2|X1=580|Y1=428|X2=690|Y2=428
|RECORD=27|IndexInSheet=451|OwnerPartId=-1|LineWidth=1|Color=8388608|LocationCount=2|X1=691|Y1=418|X2=580|Y2=418
|RECORD=27|IndexInSheet=452|OwnerPartId=-1|LineWidth=1|Color=8388608|LocationCount=2|X1=1170|Y1=918|X2=1059|Y2=918
|RECORD=27|IndexInSheet=453|OwnerPartId=-1|LineWidth=1|Color=8388608|LocationCount=2|X1=1170|Y1=908|X2=1059|Y2=908
|RECORD=27|IndexInSheet=454|OwnerPartId=-1|LineWidth=1|Color=8388608|LocationCount=2|X1=1290|Y1=918|X2=1352|Y2=918
|RECORD=27|IndexInSheet=455|OwnerPartId=-1|LineWidth=1|Color=8388608|LocationCount=2|X1=1290|Y1=908|X2=1352|Y2=908
|RECORD=27|IndexInSheet=456|OwnerPartId=-1|LineWidth=1|Color=8388608|LocationCount=2|X1=320|Y1=338|X2=460|Y2=338
|RECORD=27|IndexInSheet=457|OwnerPartId=-1|LineWidth=1|Color=8388608|LocationCount=2|X1=320|Y1=348|X2=460|Y2=348
|RECORD=27|IndexInSheet=458|OwnerPartId=-1|LineWidth=1|Color=8388608|LocationCount=2|X1=320|Y1=328|X2=460|Y2=328
|RECORD=27|IndexInSheet=459|OwnerPartId=-1|LineWidth=1|Color=8388608|LocationCount=2|X1=320|Y1=318|X2=460|Y2=318
|RECORD=27|IndexInSheet=460|OwnerPartId=-1|LineWidth=1|Color=8388608|LocationCount=2|X1=320|Y1=298|X2=460|Y2=298
|RECORD=27|IndexInSheet=461|OwnerPartId=-1|LineWidth=1|Color=8388608|LocationCount=2|X1=320|Y1=288|X2=460|Y2=288
|RECORD=27|IndexInSheet=462|OwnerPartId=-1|LineWidth=1|Color=8388608|LocationCount=2|X1=460|Y1=278|X2=320|Y2=278
|RECORD=27|IndexInSheet=463|OwnerPartId=-1|LineWidth=1|Color=8388608|LocationCount=2|X1=320|Y1=268|X2=460|Y2=268
|RECORD=27|IndexInSheet=464|OwnerPartId=-1|LineWidth=1|Color=8388608|LocationCount=2|X1=691|Y1=348|X2=580|Y2=348
|RECORD=27|IndexInSheet=465|OwnerPartId=-1|LineWidth=1|Color=8388608|LocationCount=2|X1=691|Y1=338|X2=580|Y2=338
|RECORD=27|IndexInSheet=466|OwnerPartId=-1|LineWidth=1|Color=8388608|LocationCount=2|X1=691|Y1=328|X2=580|Y2=328
|RECORD=27|IndexInSheet=467|OwnerPartId=-1|LineWidth=1|Color=8388608|LocationCount=2|X1=691|Y1=318|X2=580|Y2=318
|RECORD=27|IndexInSheet=468|OwnerPartId=-1|LineWidth=1|Color=8388608|LocationCount=2|X1=691|Y1=298|X2=580|Y2=298
|RECORD=27|IndexInSheet=469|OwnerPartId=-1|LineWidth=1|Color=8388608|LocationCount=2|X1=691|Y1=288|X2=580|Y2=288
|RECORD=27|IndexInSheet=470|OwnerPartId=-1|LineWidth=1|Color=8388608|LocationCount=2|X1=691|Y1=278|X2=580|Y2=278
|RECORD=27|IndexInSheet=471|OwnerPartId=-1|LineWidth=1|Color=8388608|LocationCount=2|X1=691|Y1=268|X2=580|Y2=268
|RECORD=27|IndexInSheet=472|OwnerPartId=-1|LineWidth=1|Color=8388608|LocationCount=2|X1=691|Y1=778|X2=580|Y2=778
|RECORD=27|IndexInSheet=473|OwnerPartId=-1|LineWidth=1|Color=8388608|LocationCount=9|X1=1290|Y1=948|X2=1320|Y2=948|X3=1320|Y3=898|X4=1320|Y4=848|X5=1320|Y5=798|X6=1320|Y6=748|X7=1320|Y7=698|X8=1320|Y8=648|X9=1320|Y9=568
|RECORD=27|IndexInSheet=474|OwnerPartId=-1|LineWidth=1|Color=8388608|LocationCount=4|X1=1170|Y1=968|X2=1135|Y2=968|X3=1135|Y3=970|X4=1125|Y4=970
|RECORD=27|IndexInSheet=475|OwnerPartId=-1|LineWidth=1|Color=8388608|LocationCount=4|X1=1170|Y1=978|X2=1140|Y2=978|X3=1140|Y3=980|X4=1125|Y4=980
|RECORD=27|IndexInSheet=476|OwnerPartId=-1|LineWidth=1|Color=8388608|LocationCount=4|X1=1170|Y1=988|X2=1145|Y2=988|X3=1145|Y3=990|X4=1125|Y4=990
|RECORD=27|IndexInSheet=477|OwnerPartId=-1|LineWidth=1|Color=8388608|LocationCount=4|X1=1290|Y1=978|X2=1315|Y2=978|X3=1315|Y3=980|X4=1345|Y4=980
|RECORD=27|IndexInSheet=478|OwnerPartId=-1|LineWidth=1|Color=8388608|LocationCount=4|X1=1290|Y1=988|X2=1310|Y2=988|X3=1310|Y3=990|X4=1345|Y4=990
|RECORD=27|IndexInSheet=479|OwnerPartId=-1|LineWidth=1|Color=8388608|LocationCount=4|X1=1290|Y1=608|X2=1395|Y2=608|X3=1395|Y3=605|X4=1415|Y4=605
|RECORD=27|IndexInSheet=480|OwnerPartId=-1|LineWidth=1|Color=8388608|LocationCount=4|X1=1290|Y1=618|X2=1380|Y2=618|X3=1380|Y3=615|X4=1415|Y4=615
|RECORD=27|IndexInSheet=481|OwnerPartId=-1|LineWidth=1|Color=8388608|LocationCount=4|X1=1170|Y1=668|X2=1025|Y2=668|X3=1025|Y3=670|X4=995|Y4=670
|RECORD=27|IndexInSheet=482|OwnerPartId=-1|LineWidth=1|Color=8388608|LocationCount=4|X1=1170|Y1=618|X2=1005|Y2=618|X3=1005|Y3=620|X4=990|Y4=620
|RECORD=27|IndexInSheet=483|OwnerPartId=-1|LineWidth=1|Color=8388608|LocationCount=4|X1=1170|Y1=628|X2=1035|Y2=628|X3=1035|Y3=630|X4=990|Y4=630
|RECORD=27|IndexInSheet=484|OwnerPartId=-1|LineWidth=1|Color=8388608|LocationCount=4|X1=1170|Y1=678|X2=1015|Y2=678|X3=1015|Y3=680|X4=995|Y4=680
|RECORD=17|IndexInSheet=485|OwnerPartId=-1|ShowNetName=T|Location.X=1360|Location.Y=815|Color=255|FontID=1|Text=FPGA_BNO_XIN32|IsCrossSheetConnector=T
|RECORD=17|IndexInSheet=486|OwnerPartId=-1|ShowNetName=T|Location.X=1360|Location.Y=805|Color=255|FontID=1|Text=FPGA_BNO_XOUT32|IsCrossSheetConnector=T
|RECORD=27|IndexInSheet=487|OwnerPartId=-1|LineWidth=1|Color=8388608|LocationCount=3|X1=1290|Y1=808|X2=1360|Y2=808|X3=1360|Y3=805
|RECORD=27|IndexInSheet=488|OwnerPartId=-1|LineWidth=1|Color=8388608|LocationCount=3|X1=1290|Y1=818|X2=1360|Y2=818|X3=1360|Y3=815
|RECORD=29|IndexInSheet=-1|OwnerPartId=-1|Location.X=400|Location.Y=158|Color=128
|RECORD=29|IndexInSheet=-1|OwnerPartId=-1|Location.X=400|Location.Y=208|Color=128
|RECORD=29|IndexInSheet=-1|OwnerPartId=-1|Location.X=400|Location.Y=258|Color=128
|RECORD=29|IndexInSheet=-1|OwnerPartId=-1|Location.X=400|Location.Y=308|Color=128
|RECORD=29|IndexInSheet=-1|OwnerPartId=-1|Location.X=400|Location.Y=358|Color=128
|RECORD=29|IndexInSheet=-1|OwnerPartId=-1|Location.X=400|Location.Y=408|Color=128
|RECORD=29|IndexInSheet=-1|OwnerPartId=-1|Location.X=410|Location.Y=648|Color=128
|RECORD=29|IndexInSheet=-1|OwnerPartId=-1|Location.X=410|Location.Y=698|Color=128
|RECORD=29|IndexInSheet=-1|OwnerPartId=-1|Location.X=410|Location.Y=748|Color=128
|RECORD=29|IndexInSheet=-1|OwnerPartId=-1|Location.X=410|Location.Y=798|Color=128
|RECORD=29|IndexInSheet=-1|OwnerPartId=-1|Location.X=410|Location.Y=848|Color=128
|RECORD=29|IndexInSheet=-1|OwnerPartId=-1|Location.X=410|Location.Y=898|Color=128
|RECORD=29|IndexInSheet=-1|OwnerPartId=-1|Location.X=410|Location.Y=968|Color=128
|RECORD=29|IndexInSheet=-1|OwnerPartId=-1|Location.X=410|Location.Y=978|Color=128
|RECORD=29|IndexInSheet=-1|OwnerPartId=-1|Location.X=410|Location.Y=988|Color=128
|RECORD=29|IndexInSheet=-1|OwnerPartId=-1|Location.X=600|Location.Y=648|Color=128
|RECORD=29|IndexInSheet=-1|OwnerPartId=-1|Location.X=600|Location.Y=698|Color=128
|RECORD=29|IndexInSheet=-1|OwnerPartId=-1|Location.X=600|Location.Y=748|Color=128
|RECORD=29|IndexInSheet=-1|OwnerPartId=-1|Location.X=600|Location.Y=798|Color=128
|RECORD=29|IndexInSheet=-1|OwnerPartId=-1|Location.X=600|Location.Y=848|Color=128
|RECORD=29|IndexInSheet=-1|OwnerPartId=-1|Location.X=600|Location.Y=898|Color=128
|RECORD=29|IndexInSheet=-1|OwnerPartId=-1|Location.X=600|Location.Y=968|Color=128
|RECORD=29|IndexInSheet=-1|OwnerPartId=-1|Location.X=600|Location.Y=978|Color=128
|RECORD=29|IndexInSheet=-1|OwnerPartId=-1|Location.X=600|Location.Y=988|Color=128
|RECORD=29|IndexInSheet=-1|OwnerPartId=-1|Location.X=620|Location.Y=158|Color=128
|RECORD=29|IndexInSheet=-1|OwnerPartId=-1|Location.X=620|Location.Y=208|Color=128
|RECORD=29|IndexInSheet=-1|OwnerPartId=-1|Location.X=620|Location.Y=258|Color=128
|RECORD=29|IndexInSheet=-1|OwnerPartId=-1|Location.X=620|Location.Y=308|Color=128
|RECORD=29|IndexInSheet=-1|OwnerPartId=-1|Location.X=620|Location.Y=358|Color=128
|RECORD=29|IndexInSheet=-1|OwnerPartId=-1|Location.X=620|Location.Y=408|Color=128
|RECORD=29|IndexInSheet=-1|OwnerPartId=-1|Location.X=1110|Location.Y=158|Color=128
|RECORD=29|IndexInSheet=-1|OwnerPartId=-1|Location.X=1110|Location.Y=208|Color=128
|RECORD=29|IndexInSheet=-1|OwnerPartId=-1|Location.X=1110|Location.Y=258|Color=128
|RECORD=29|IndexInSheet=-1|OwnerPartId=-1|Location.X=1110|Location.Y=308|Color=128
|RECORD=29|IndexInSheet=-1|OwnerPartId=-1|Location.X=1110|Location.Y=338|Color=128
|RECORD=29|IndexInSheet=-1|OwnerPartId=-1|Location.X=1110|Location.Y=368|Color=128
|RECORD=29|IndexInSheet=-1|OwnerPartId=-1|Location.X=1110|Location.Y=398|Color=128
|RECORD=29|IndexInSheet=-1|OwnerPartId=-1|Location.X=1110|Location.Y=428|Color=128
|RECORD=29|IndexInSheet=-1|OwnerPartId=-1|Location.X=1130|Location.Y=648|Color=128
|RECORD=29|IndexInSheet=-1|OwnerPartId=-1|Location.X=1130|Location.Y=698|Color=128
|RECORD=29|IndexInSheet=-1|OwnerPartId=-1|Location.X=1130|Location.Y=748|Color=128
|RECORD=29|IndexInSheet=-1|OwnerPartId=-1|Location.X=1130|Location.Y=798|Color=128
|RECORD=29|IndexInSheet=-1|OwnerPartId=-1|Location.X=1130|Location.Y=848|Color=128
|RECORD=29|IndexInSheet=-1|OwnerPartId=-1|Location.X=1130|Location.Y=898|Color=128
|RECORD=29|IndexInSheet=-1|OwnerPartId=-1|Location.X=1160|Location.Y=938|Color=128
|RECORD=29|IndexInSheet=-1|OwnerPartId=-1|Location.X=1310|Location.Y=158|Color=128
|RECORD=29|IndexInSheet=-1|OwnerPartId=-1|Location.X=1310|Location.Y=208|Color=128
|RECORD=29|IndexInSheet=-1|OwnerPartId=-1|Location.X=1310|Location.Y=258|Color=128
|RECORD=29|IndexInSheet=-1|OwnerPartId=-1|Location.X=1310|Location.Y=308|Color=128
|RECORD=29|IndexInSheet=-1|OwnerPartId=-1|Location.X=1320|Location.Y=648|Color=128
|RECORD=29|IndexInSheet=-1|OwnerPartId=-1|Location.X=1320|Location.Y=698|Color=128
|RECORD=29|IndexInSheet=-1|OwnerPartId=-1|Location.X=1320|Location.Y=748|Color=128
|RECORD=29|IndexInSheet=-1|OwnerPartId=-1|Location.X=1320|Location.Y=798|Color=128
|RECORD=29|IndexInSheet=-1|OwnerPartId=-1|Location.X=1320|Location.Y=848|Color=128
|RECORD=29|IndexInSheet=-1|OwnerPartId=-1|Location.X=1320|Location.Y=898|Color=128